FILE_TYPE = MACRO_DRAWING;
SET COLOR_WIRE YELLOW;
SET COLOR_PROP MONO;
SET COLOR_DOT WHITE;
SET COLOR_ARC YELLOW;
SET COLOR_BODY GREEN;
SET COLOR_NOTE MONO;
SET PROP_DISPLAY VALUE;
SET PAGE_NUMBER P145;
FORCEADD RES..1
(-4450 -250);
FORCEPROP 1 LAST PACK_TYPE 0402
J 0
(-4200 -400);
DISPLAY 0.617021 (-4200 -400);
PAINT SKYBLUE (-4200 -400);
FORCEPROP 1 LAST PART_NUMBER G21497-005
J 0
(-4325 -225);
DISPLAY 0.617021 (-4325 -225);
PAINT BLUE (-4325 -225);
FORCEPROP 1 LASTPIN (-4350 -250) $PN 2
J 0
(-4388 -238);
DISPLAY 0.617021 (-4388 -238);
PAINT ORANGE (-4388 -238);
FORCEPROP 1 LAST LOCATION R9F60
J 0
(-4500 -150);
DISPLAY 0.617021 (-4500 -150);
PAINT AQUA (-4500 -150);
FORCEPROP 1 LASTPIN (-4550 -250) $PN 1
J 0
(-4538 -238);
DISPLAY 0.617021 (-4538 -238);
PAINT ORANGE (-4538 -238);
FORCEPROP 1 LAST WATTAGE 1/16W
J 2
(-4475 -400);
DISPLAY 0.617021 (-4475 -400);
PAINT SKYBLUE (-4475 -400);
FORCEPROP 1 LAST VALUE 0.0
J 2
(-4525 -350);
DISPLAY 0.617021 (-4525 -350);
PAINT SKYBLUE (-4525 -350);
FORCEPROP 1 LAST MATERIAL EMPTY
J 0
(-4450 -400);
DISPLAY 0.617021 (-4450 -400);
PAINT RED (-4450 -400);
FORCEPROP 1 LAST TOLERANCE 5%
J 0
(-4350 -350);
DISPLAY 0.617021 (-4350 -350);
PAINT SKYBLUE (-4350 -350);
FORCEPROP 0 LAST CDS_SEC 1
J 0
(-4500 -100);
PAINT MONO (-4500 -100);
DISPLAY INVISIBLE (-4500 -100);
FORCEPROP 0 LAST CDS_LOCATION R9F60
J 0
(-4500 -100);
PAINT MONO (-4500 -100);
DISPLAY INVISIBLE (-4500 -100);
FORCEPROP 0 LAST BOM_COST SM_CONTROLLER
J 0
(-4500 50);
DISPLAY 1.021277 (-4500 50);
PAINT ORANGE (-4500 50);
DISPLAY INVISIBLE (-4500 50);
FORCEPROP 2 LAST SEC 1
J 0
(-4500 -50);
DISPLAY 0.680851 (-4500 -50);
PAINT MONO (-4500 -50);
DISPLAY INVISIBLE (-4500 -50);
FORCEPROP 2 LAST SEC_TYPE 0402
J 0
(-4500 -50);
DISPLAY 1.021277 (-4500 -50);
PAINT ORANGE (-4500 -50);
DISPLAY INVISIBLE (-4500 -50);
FORCEPROP 0 LAST ROOM BMC
J 0
(-4500 -50);
DISPLAY 1.021277 (-4500 -50);
PAINT ORANGE (-4500 -50);
DISPLAY INVISIBLE (-4500 -50);
FORCEPROP 2 LAST CDS_LIB mstr_discrete
J 0
(-4450 -250);
PAINT ORANGE (-4450 -250);
DISPLAY INVISIBLE (-4450 -250);
FORCEPROP 1 LAST PATH I10
J 0
(-4500 -100);
DISPLAY 0.978723 (-4500 -100);
PAINT WHITE (-4500 -100);
DISPLAY INVISIBLE (-4500 -100);
FORCEADD RES..1
(-7300 -3975);
FORCEPROP 1 LAST PACK_TYPE 0402
J 0
(-7350 -4375);
DISPLAY 0.617021 (-7350 -4375);
PAINT SKYBLUE (-7350 -4375);
FORCEPROP 1 LASTPIN (-7400 -3975) $PN 1
J 0
(-7388 -3963);
DISPLAY 0.787234 (-7388 -3963);
PAINT ORANGE (-7388 -3963);
FORCEPROP 1 LAST WATTAGE 1/16W
J 2
(-7250 -4225);
DISPLAY 0.617021 (-7250 -4225);
PAINT SKYBLUE (-7250 -4225);
FORCEPROP 1 LAST TOLERANCE 5%
J 0
(-7350 -4175);
DISPLAY 0.617021 (-7350 -4175);
PAINT SKYBLUE (-7350 -4175);
FORCEPROP 1 LAST VALUE 0.0
J 2
(-7300 -4125);
DISPLAY 0.617021 (-7300 -4125);
PAINT SKYBLUE (-7300 -4125);
FORCEPROP 1 LASTPIN (-7200 -3975) $PN 2
J 0
(-7238 -3963);
DISPLAY 0.787234 (-7238 -3963);
PAINT ORANGE (-7238 -3963);
FORCEPROP 1 LAST LOCATION R1T15
J 0
(-7375 -3875);
DISPLAY 0.617021 (-7375 -3875);
PAINT AQUA (-7375 -3875);
FORCEPROP 1 LAST MATERIAL EMPTY
J 0
(-7350 -4275);
DISPLAY 0.617021 (-7350 -4275);
PAINT RED (-7350 -4275);
FORCEPROP 1 LAST PART_NUMBER G21497-005
J 0
(-7350 -4325);
DISPLAY 0.617021 (-7350 -4325);
PAINT BLUE (-7350 -4325);
FORCEPROP 2 LAST CDS_LIB mstr_discrete
J 0
(-7300 -3975);
PAINT MONO (-7300 -3975);
DISPLAY INVISIBLE (-7300 -3975);
FORCEPROP 1 LAST PATH I100
J 0
(-7350 -3825);
DISPLAY 0.978723 (-7350 -3825);
PAINT WHITE (-7350 -3825);
DISPLAY INVISIBLE (-7350 -3825);
FORCEPROP 2 LAST SEC_TYPE 0402
J 0
(-7350 -3775);
DISPLAY 1.021277 (-7350 -3775);
PAINT ORANGE (-7350 -3775);
DISPLAY INVISIBLE (-7350 -3775);
FORCEPROP 0 LAST SEC 1
J 0
(-7200 -3875);
DISPLAY 0.680851 (-7200 -3875);
PAINT MONO (-7200 -3875);
DISPLAY INVISIBLE (-7200 -3875);
FORCEADD RES..1
R 5
(-7050 -4200);
FORCEPROP 1 LAST LOCATION R1T23
J 0
(-6975 -4075);
DISPLAY 0.617021 (-6975 -4075);
PAINT AQUA (-6975 -4075);
FORCEPROP 1 LASTPIN (-7050 -4100) $PN 1
J 0
(-7038 -4112);
DISPLAY 0.787234 (-7038 -4112);
PAINT ORANGE (-7038 -4112);
FORCEPROP 1 LAST TOLERANCE 5%
J 0
(-6975 -4175);
DISPLAY 0.617021 (-6975 -4175);
PAINT SKYBLUE (-6975 -4175);
FORCEPROP 1 LAST MATERIAL EMPTY
J 0
(-6975 -4275);
DISPLAY 0.617021 (-6975 -4275);
PAINT RED (-6975 -4275);
FORCEPROP 1 LAST VALUE 0.0
J 2
(-6925 -4125);
DISPLAY 0.617021 (-6925 -4125);
PAINT SKYBLUE (-6925 -4125);
FORCEPROP 1 LAST WATTAGE 1/16W
J 2
(-6875 -4225);
DISPLAY 0.617021 (-6875 -4225);
PAINT SKYBLUE (-6875 -4225);
FORCEPROP 1 LASTPIN (-7050 -4300) $PN 2
J 0
(-7038 -4312);
DISPLAY 0.787234 (-7038 -4312);
PAINT ORANGE (-7038 -4312);
FORCEPROP 1 LAST PACK_TYPE 0402
J 0
(-6975 -4375);
DISPLAY 0.617021 (-6975 -4375);
PAINT SKYBLUE (-6975 -4375);
FORCEPROP 1 LAST PART_NUMBER G21497-005
J 0
(-6975 -4325);
DISPLAY 0.617021 (-6975 -4325);
PAINT BLUE (-6975 -4325);
FORCEPROP 2 LAST SEC_TYPE 0402
J 0
(-7025 -4075);
DISPLAY 1.021277 (-7025 -4075);
PAINT ORANGE (-7025 -4075);
DISPLAY INVISIBLE (-7025 -4075);
FORCEPROP 0 LAST SEC 1
J 0
(-7025 -4075);
DISPLAY 0.680851 (-7025 -4075);
PAINT MONO (-7025 -4075);
DISPLAY INVISIBLE (-7025 -4075);
FORCEPROP 1 LAST PATH I101
R 3
J 0
(-6900 -4150);
DISPLAY 0.978723 (-6900 -4150);
PAINT WHITE (-6900 -4150);
DISPLAY INVISIBLE (-6900 -4150);
FORCEPROP 2 LAST CDS_LIB mstr_discrete
R 3
J 0
(-7050 -4200);
PAINT MONO (-7050 -4200);
DISPLAY INVISIBLE (-7050 -4200);
FORCEADD GND..1
(-7050 -4400);
FORCEPROP 3 LASTPIN (-7050 -4350) SIG_NAME GND\g
J 0
(-7040 -4340);
DISPLAY 0.659574 (-7040 -4340);
PAINT MONO (-7040 -4340);
DISPLAY INVISIBLE (-7040 -4340);
FORCEPROP 1 LAST HDL_POWER GND
J 0
(-7050 -4250);
DISPLAY 0.872340 (-7050 -4250);
PAINT GREEN (-7050 -4250);
DISPLAY INVISIBLE (-7050 -4250);
FORCEPROP 1 LAST BODY_TYPE PLUMBING
J 0
(-7095 -4443);
DISPLAY 0.340426 (-7095 -4443);
PAINT GREEN (-7095 -4443);
DISPLAY INVISIBLE (-7095 -4443);
FORCEPROP 1 LAST SIZE 1B
J 0
(-6975 -4450);
DISPLAY 0.872340 (-6975 -4450);
PAINT AQUA (-6975 -4450);
DISPLAY INVISIBLE (-6975 -4450);
FORCEPROP 1 LAST VOLTAGE 0.0V
J 0
(-7095 -4443);
DISPLAY 0.340426 (-7095 -4443);
PAINT GREEN (-7095 -4443);
DISPLAY INVISIBLE (-7095 -4443);
FORCEPROP 1 LAST PATH I102
J 0
(-6975 -4400);
DISPLAY 0.872340 (-6975 -4400);
PAINT AQUA (-6975 -4400);
DISPLAY INVISIBLE (-6975 -4400);
FORCEPROP 2 LAST CDS_LIB mstr_symbols
J 0
(-7050 -4400);
PAINT MONO (-7050 -4400);
DISPLAY INVISIBLE (-7050 -4400);
FORCEADD OFFPAGE..3
(-6550 -3975);
FORCEPROP 2 LAST $XR0 145 
J 0
(-6186 -3975);
DISPLAY 0.638298 (-6186 -3975);
PAINT MONO (-6186 -3975);
FORCEPROP 1 LAST COMMENT_BODY TRUE
J 0
(-6600 -4075);
DISPLAY 0.872340 (-6600 -4075);
PAINT GREEN (-6600 -4075);
DISPLAY INVISIBLE (-6600 -4075);
FORCEPROP 1 LAST OFFPAGE TRUE
J 0
(-6225 -4100);
DISPLAY 0.872340 (-6225 -4100);
PAINT GREEN (-6225 -4100);
DISPLAY INVISIBLE (-6225 -4100);
FORCEPROP 2 LAST PATH I103
J 0
(-6350 -3900);
DISPLAY 1.021277 (-6350 -3900);
PAINT ORANGE (-6350 -3900);
DISPLAY INVISIBLE (-6350 -3900);
FORCEPROP 2 LAST CDS_LIB mstr_standard
J 0
(-6550 -3975);
PAINT MONO (-6550 -3975);
DISPLAY INVISIBLE (-6550 -3975);
FORCEADD OFFPAGE..5
(-8000 -3975);
FORCEPROP 2 LAST $XR0 191 
J 0
(-8255 -3975);
DISPLAY 0.638298 (-8255 -3975);
PAINT MONO (-8255 -3975);
FORCEPROP 1 LAST COMMENT_BODY TRUE
J 0
(-7900 -4050);
DISPLAY 0.872340 (-7900 -4050);
PAINT GREEN (-7900 -4050);
DISPLAY INVISIBLE (-7900 -4050);
FORCEPROP 1 LAST OFFPAGE TRUE
J 0
(-7675 -4100);
DISPLAY 0.872340 (-7675 -4100);
PAINT GREEN (-7675 -4100);
DISPLAY INVISIBLE (-7675 -4100);
FORCEPROP 2 LAST PATH I104
J 0
(-7950 -3900);
DISPLAY 1.021277 (-7950 -3900);
PAINT ORANGE (-7950 -3900);
DISPLAY INVISIBLE (-7950 -3900);
FORCEPROP 2 LAST CDS_LIB mstr_standard
J 0
(-8000 -3975);
PAINT MONO (-8000 -3975);
DISPLAY INVISIBLE (-8000 -3975);
FORCEADD RES..1
(-4450 -550);
FORCEPROP 1 LASTPIN (-4550 -550) $PN 1
J 0
(-4538 -538);
DISPLAY 0.617021 (-4538 -538);
PAINT ORANGE (-4538 -538);
FORCEPROP 1 LAST TOLERANCE 5%
J 0
(-4450 -650);
DISPLAY 0.617021 (-4450 -650);
PAINT SKYBLUE (-4450 -650);
FORCEPROP 1 LAST PACK_TYPE 0402
J 0
(-4200 -700);
DISPLAY 0.617021 (-4200 -700);
PAINT SKYBLUE (-4200 -700);
FORCEPROP 1 LAST PART_NUMBER G21497-005
J 0
(-4500 -450);
DISPLAY 0.617021 (-4500 -450);
PAINT BLUE (-4500 -450);
FORCEPROP 1 LAST LOCATION R9F62
J 0
(-4500 -500);
DISPLAY 0.617021 (-4500 -500);
PAINT AQUA (-4500 -500);
FORCEPROP 1 LASTPIN (-4350 -550) $PN 2
J 0
(-4388 -538);
DISPLAY 0.617021 (-4388 -538);
PAINT ORANGE (-4388 -538);
FORCEPROP 1 LAST VALUE 0.0
J 2
(-4475 -650);
DISPLAY 0.617021 (-4475 -650);
PAINT SKYBLUE (-4475 -650);
FORCEPROP 1 LAST WATTAGE 1/16W
J 2
(-4475 -700);
DISPLAY 0.617021 (-4475 -700);
PAINT SKYBLUE (-4475 -700);
FORCEPROP 1 LAST MATERIAL CHIP
J 0
(-4450 -700);
DISPLAY 0.617021 (-4450 -700);
PAINT SKYBLUE (-4450 -700);
FORCEPROP 0 LAST CDS_SEC 1
J 0
(-4500 -400);
PAINT MONO (-4500 -400);
DISPLAY INVISIBLE (-4500 -400);
FORCEPROP 0 LAST CDS_LOCATION R9F62
J 0
(-4500 -400);
PAINT MONO (-4500 -400);
DISPLAY INVISIBLE (-4500 -400);
FORCEPROP 0 LAST BOM_COST SM_CONTROLLER
J 0
(-4500 -250);
DISPLAY 1.021277 (-4500 -250);
PAINT ORANGE (-4500 -250);
DISPLAY INVISIBLE (-4500 -250);
FORCEPROP 0 LAST ROOM BMC
J 0
(-4500 -350);
DISPLAY 1.021277 (-4500 -350);
PAINT ORANGE (-4500 -350);
DISPLAY INVISIBLE (-4500 -350);
FORCEPROP 2 LAST SEC_TYPE 0402
J 0
(-4500 -350);
DISPLAY 1.021277 (-4500 -350);
PAINT ORANGE (-4500 -350);
DISPLAY INVISIBLE (-4500 -350);
FORCEPROP 2 LAST SEC 1
J 0
(-4500 -350);
DISPLAY 0.680851 (-4500 -350);
PAINT MONO (-4500 -350);
DISPLAY INVISIBLE (-4500 -350);
FORCEPROP 2 LAST CDS_LIB mstr_discrete
J 0
(-4450 -550);
PAINT ORANGE (-4450 -550);
DISPLAY INVISIBLE (-4450 -550);
FORCEPROP 1 LAST PATH I11
J 0
(-4500 -400);
DISPLAY 0.978723 (-4500 -400);
PAINT WHITE (-4500 -400);
DISPLAY INVISIBLE (-4500 -400);
FORCEADD AST2520A1-GP-GP..3
(-3800 -2550);
FORCEPROP 2 LASTPIN (-5100 -3250) $PN AB18
J 2
(-5110 -3240);
DISPLAY 0.808511 (-5110 -3240);
PAINT ORANGE (-5110 -3240);
FORCEPROP 2 LASTPIN (-5100 -3150) $PN B14
J 2
(-5110 -3140);
DISPLAY 0.808511 (-5110 -3140);
PAINT ORANGE (-5110 -3140);
FORCEPROP 2 LASTPIN (-2500 -2900) $PN F18
J 0
(-2490 -2890);
DISPLAY 0.808511 (-2490 -2890);
PAINT ORANGE (-2490 -2890);
FORCEPROP 2 LASTPIN (-2500 -2950) $PN C20
J 0
(-2490 -2940);
DISPLAY 0.808511 (-2490 -2940);
PAINT ORANGE (-2490 -2940);
FORCEPROP 2 LASTPIN (-2500 -3000) $PN B20
J 0
(-2490 -2990);
DISPLAY 0.808511 (-2490 -2990);
PAINT ORANGE (-2490 -2990);
FORCEPROP 2 LASTPIN (-2500 -3100) $PN K1
J 0
(-2490 -3090);
DISPLAY 0.808511 (-2490 -3090);
PAINT ORANGE (-2490 -3090);
FORCEPROP 2 LASTPIN (-5100 -2950) $PN E13
J 2
(-5110 -2940);
DISPLAY 0.808511 (-5110 -2940);
PAINT ORANGE (-5110 -2940);
FORCEPROP 2 LASTPIN (-5100 -2700) $PN P21
J 2
(-5110 -2690);
DISPLAY 0.808511 (-5110 -2690);
PAINT ORANGE (-5110 -2690);
FORCEPROP 2 LASTPIN (-5100 -1750) $PN F19
J 2
(-5110 -1740);
DISPLAY 0.808511 (-5110 -1740);
PAINT ORANGE (-5110 -1740);
FORCEPROP 2 LASTPIN (-5100 -1850) $PN B11
J 2
(-5110 -1840);
DISPLAY 0.808511 (-5110 -1840);
PAINT ORANGE (-5110 -1840);
FORCEPROP 2 LASTPIN (-5100 -1900) $PN C11
J 2
(-5110 -1890);
DISPLAY 0.808511 (-5110 -1890);
PAINT ORANGE (-5110 -1890);
FORCEPROP 2 LASTPIN (-5100 -2000) $PN E12
J 2
(-5110 -1990);
DISPLAY 0.808511 (-5110 -1990);
PAINT ORANGE (-5110 -1990);
FORCEPROP 2 LASTPIN (-5100 -2050) $PN D10
J 2
(-5110 -2040);
DISPLAY 0.808511 (-5110 -2040);
PAINT ORANGE (-5110 -2040);
FORCEPROP 2 LASTPIN (-5100 -2200) $PN B12
J 2
(-5110 -2190);
DISPLAY 0.808511 (-5110 -2190);
PAINT ORANGE (-5110 -2190);
FORCEPROP 2 LASTPIN (-5100 -1300) $PN C21
J 2
(-5110 -1290);
DISPLAY 0.808511 (-5110 -1290);
PAINT ORANGE (-5110 -1290);
FORCEPROP 2 LASTPIN (-5100 -1550) $PN D20
J 2
(-5110 -1540);
DISPLAY 0.808511 (-5110 -1540);
PAINT ORANGE (-5110 -1540);
FORCEPROP 2 LASTPIN (-5100 -1600) $PN F20
J 2
(-5110 -1590);
DISPLAY 0.808511 (-5110 -1590);
PAINT ORANGE (-5110 -1590);
FORCEPROP 2 LASTPIN (-5100 -1450) $PN E20
J 2
(-5110 -1440);
DISPLAY 0.808511 (-5110 -1440);
PAINT ORANGE (-5110 -1440);
FORCEPROP 2 LASTPIN (-5100 -1500) $PN D21
J 2
(-5110 -1490);
DISPLAY 0.808511 (-5110 -1490);
PAINT ORANGE (-5110 -1490);
FORCEPROP 2 LASTPIN (-5100 -1700) $PN E21
J 2
(-5110 -1690);
DISPLAY 0.808511 (-5110 -1690);
PAINT ORANGE (-5110 -1690);
FORCEPROP 2 LASTPIN (-5100 -2450) $PN E14
J 2
(-5110 -2440);
DISPLAY 0.808511 (-5110 -2440);
PAINT ORANGE (-5110 -2440);
FORCEPROP 2 LASTPIN (-5100 -3600) $PN K22
J 2
(-5110 -3590);
DISPLAY 0.808511 (-5110 -3590);
PAINT ORANGE (-5110 -3590);
FORCEPROP 2 LASTPIN (-5100 -2150) $PN D9
J 2
(-5110 -2140);
DISPLAY 0.808511 (-5110 -2140);
PAINT ORANGE (-5110 -2140);
FORCEPROP 2 LASTPIN (-5100 -2350) $PN C12
J 2
(-5110 -2340);
DISPLAY 0.808511 (-5110 -2340);
PAINT ORANGE (-5110 -2340);
FORCEPROP 2 LASTPIN (-2500 -2400) $PN B21
J 0
(-2490 -2390);
DISPLAY 0.808511 (-2490 -2390);
PAINT ORANGE (-2490 -2390);
FORCEPROP 2 LASTPIN (-2500 -2100) $PN T2
J 0
(-2490 -2090);
DISPLAY 0.808511 (-2490 -2090);
PAINT ORANGE (-2490 -2090);
FORCEPROP 2 LASTPIN (-2500 -2450) $PN B22
J 0
(-2490 -2440);
DISPLAY 0.808511 (-2490 -2440);
PAINT ORANGE (-2490 -2440);
FORCEPROP 2 LASTPIN (-2500 -1800) $PN V1
J 0
(-2490 -1790);
DISPLAY 0.808511 (-2490 -1790);
PAINT ORANGE (-2490 -1790);
FORCEPROP 2 LASTPIN (-2500 -2250) $PN G17
J 0
(-2490 -2240);
DISPLAY 0.808511 (-2490 -2240);
PAINT ORANGE (-2490 -2240);
FORCEPROP 2 LASTPIN (-2500 -2750) $PN D19
J 0
(-2490 -2740);
DISPLAY 0.808511 (-2490 -2740);
PAINT ORANGE (-2490 -2740);
FORCEPROP 2 LASTPIN (-2500 -3300) $PN L21
J 0
(-2490 -3290);
DISPLAY 0.808511 (-2490 -3290);
PAINT ORANGE (-2490 -3290);
FORCEPROP 2 LASTPIN (-2500 -2800) $PN E18
J 0
(-2490 -2790);
DISPLAY 0.808511 (-2490 -2790);
PAINT ORANGE (-2490 -2790);
FORCEPROP 2 LASTPIN (-2500 -2850) $PN F17
J 0
(-2490 -2840);
DISPLAY 0.808511 (-2490 -2840);
PAINT ORANGE (-2490 -2840);
FORCEPROP 2 LASTPIN (-2500 -2050) $PN T1
J 0
(-2490 -2040);
DISPLAY 0.808511 (-2490 -2040);
PAINT ORANGE (-2490 -2040);
FORCEPROP 2 LASTPIN (-2500 -1350) $PN R5
J 0
(-2490 -1340);
DISPLAY 0.808511 (-2490 -1340);
PAINT ORANGE (-2490 -1340);
FORCEPROP 2 LASTPIN (-2500 -1400) $PN P5
J 0
(-2490 -1390);
DISPLAY 0.808511 (-2490 -1390);
PAINT ORANGE (-2490 -1390);
FORCEPROP 2 LASTPIN (-2500 -2000) $PN U1
J 0
(-2490 -1990);
DISPLAY 0.808511 (-2490 -1990);
PAINT ORANGE (-2490 -1990);
FORCEPROP 2 LASTPIN (-2500 -3350) $PN L22
J 0
(-2490 -3340);
DISPLAY 0.808511 (-2490 -3340);
PAINT ORANGE (-2490 -3340);
FORCEPROP 2 LASTPIN (-2500 -1550) $PN AA1
J 0
(-2490 -1540);
DISPLAY 0.808511 (-2490 -1540);
PAINT ORANGE (-2490 -1540);
FORCEPROP 2 LASTPIN (-2500 -1300) $PN T5
J 0
(-2490 -1290);
DISPLAY 0.808511 (-2490 -1290);
PAINT ORANGE (-2490 -1290);
FORCEPROP 2 LASTPIN (-2500 -1500) $PN Y2
J 0
(-2490 -1490);
DISPLAY 0.808511 (-2490 -1490);
PAINT ORANGE (-2490 -1490);
FORCEPROP 2 LASTPIN (-2500 -1450) $PN AA2
J 0
(-2490 -1440);
DISPLAY 0.808511 (-2490 -1440);
PAINT ORANGE (-2490 -1440);
FORCEPROP 2 LASTPIN (-2500 -1650) $PN Y1
J 0
(-2490 -1640);
DISPLAY 0.808511 (-2490 -1640);
PAINT ORANGE (-2490 -1640);
FORCEPROP 2 LASTPIN (-2500 -2200) $PN H18
J 0
(-2490 -2190);
DISPLAY 0.808511 (-2490 -2190);
PAINT ORANGE (-2490 -2190);
FORCEPROP 2 LASTPIN (-2500 -1950) $PN U2
J 0
(-2490 -1940);
DISPLAY 0.808511 (-2490 -1940);
PAINT ORANGE (-2490 -1940);
FORCEPROP 2 LASTPIN (-2500 -2300) $PN H19
J 0
(-2490 -2290);
DISPLAY 0.808511 (-2490 -2290);
PAINT ORANGE (-2490 -2290);
FORCEPROP 2 LASTPIN (-5100 -1350) $PN G18
J 2
(-5110 -1340);
DISPLAY 0.808511 (-5110 -1340);
PAINT ORANGE (-5110 -1340);
FORCEPROP 2 LASTPIN (-5100 -3450) $PN L20
J 2
(-5110 -3440);
DISPLAY 0.808511 (-5110 -3440);
PAINT ORANGE (-5110 -3440);
FORCEPROP 1 LAST LOCATION U25W4
J 0
(-4950 -1125);
DISPLAY 0.617021 (-4950 -1125);
PAINT GREEN (-4950 -1125);
FORCEPROP 2 LASTPIN (-2500 -2350) $PN A21
J 0
(-2490 -2340);
DISPLAY 0.808511 (-2490 -2340);
PAINT ORANGE (-2490 -2340);
FORCEPROP 2 LASTPIN (-2500 -2700) $PN A20
J 0
(-2490 -2690);
DISPLAY 0.808511 (-2490 -2690);
PAINT ORANGE (-2490 -2690);
FORCEPROP 2 LASTPIN (-5100 -2500) $PN D15
J 2
(-5110 -2490);
DISPLAY 0.808511 (-5110 -2490);
PAINT ORANGE (-5110 -2490);
FORCEPROP 2 LASTPIN (-2500 -2650) $PN B19
J 0
(-2490 -2640);
DISPLAY 0.808511 (-2490 -2640);
PAINT ORANGE (-2490 -2640);
FORCEPROP 2 LASTPIN (-2500 -2550) $PN J19
J 0
(-2490 -2540);
DISPLAY 0.808511 (-2490 -2540);
PAINT ORANGE (-2490 -2540);
FORCEPROP 2 LASTPIN (-2500 -2500) $PN J18
J 0
(-2490 -2490);
DISPLAY 0.808511 (-2490 -2490);
PAINT ORANGE (-2490 -2490);
FORCEPROP 2 LASTPIN (-5100 -2300) $PN A12
J 2
(-5110 -2290);
DISPLAY 0.808511 (-5110 -2290);
PAINT ORANGE (-5110 -2290);
FORCEPROP 2 LASTPIN (-5100 -2550) $PN D16
J 2
(-5110 -2540);
DISPLAY 0.808511 (-5110 -2540);
PAINT ORANGE (-5110 -2540);
FORCEPROP 2 LASTPIN (-5100 -2600) $PN E17
J 2
(-5110 -2590);
DISPLAY 0.808511 (-5110 -2590);
PAINT ORANGE (-5110 -2590);
FORCEPROP 2 LASTPIN (-5100 -3350) $PN K2
J 2
(-5110 -3340);
DISPLAY 0.808511 (-5110 -3340);
PAINT ORANGE (-5110 -3340);
FORCEPROP 2 LASTPIN (-5100 -3000) $PN D13
J 2
(-5110 -2990);
DISPLAY 0.808511 (-5110 -2990);
PAINT ORANGE (-5110 -2990);
FORCEPROP 2 LASTPIN (-5100 -2850) $PN W18
J 2
(-5110 -2840);
DISPLAY 0.808511 (-5110 -2840);
PAINT ORANGE (-5110 -2840);
FORCEPROP 2 LASTPIN (-5100 -2800) $PN U18
J 2
(-5110 -2790);
DISPLAY 0.808511 (-5110 -2790);
PAINT ORANGE (-5110 -2790);
FORCEPROP 2 LASTPIN (-5100 -3550) $PN K21
J 2
(-5110 -3540);
DISPLAY 0.808511 (-5110 -3540);
PAINT ORANGE (-5110 -3540);
FORCEPROP 1 LAST VALUE AST2520A1-GP-GP
J 0
(-4950 -4000);
DISPLAY 0.617021 (-4950 -4000);
PAINT GREEN (-4950 -4000);
FORCEPROP 2 LASTPIN (-5100 -3750) $PN M22
J 2
(-5110 -3740);
DISPLAY 0.808511 (-5110 -3740);
PAINT ORANGE (-5110 -3740);
FORCEPROP 2 LASTPIN (-5100 -3700) $PN M21
J 2
(-5110 -3690);
DISPLAY 0.808511 (-5110 -3690);
PAINT ORANGE (-5110 -3690);
FORCEPROP 2 LASTPIN (-2500 -3200) $PN K20
J 0
(-2490 -3190);
DISPLAY 0.808511 (-2490 -3190);
PAINT ORANGE (-2490 -3190);
FORCEPROP 2 LASTPIN (-2500 -1900) $PN P4
J 0
(-2490 -1890);
DISPLAY 0.808511 (-2490 -1890);
PAINT ORANGE (-2490 -1890);
FORCEPROP 2 LASTPIN (-2500 -1850) $PN P3
J 0
(-2490 -1840);
DISPLAY 0.808511 (-2490 -1840);
PAINT ORANGE (-2490 -1840);
FORCEPROP 2 LASTPIN (-2500 -1600) $PN AB2
J 0
(-2490 -1590);
DISPLAY 0.808511 (-2490 -1590);
PAINT ORANGE (-2490 -1590);
FORCEPROP 2 LASTPIN (-2500 -1750) $PN W1
J 0
(-2490 -1740);
DISPLAY 0.808511 (-2490 -1740);
PAINT ORANGE (-2490 -1740);
FORCEPROP 2 LASTPIN (-5100 -3100) $PN D14
J 2
(-5110 -3090);
DISPLAY 0.808511 (-5110 -3090);
PAINT ORANGE (-5110 -3090);
FORCEPROP 2 LAST CDS_LIB w_hdl
J 0
(-3800 -2550);
PAINT MONO (-3800 -2550);
DISPLAY INVISIBLE (-3800 -2550);
FORCEPROP 1 LAST PART_NUMBER 071.2520A.M001
J 0
(-3800 -2550);
DISPLAY 0.617021 (-3800 -2550);
PAINT GREEN (-3800 -2550);
DISPLAY INVISIBLE (-3800 -2550);
FORCEPROP 1 LAST PATH I117
J 0
(-3800 -2550);
DISPLAY 0.617021 (-3800 -2550);
PAINT GREEN (-3800 -2550);
DISPLAY INVISIBLE (-3800 -2550);
FORCEPROP 1 LAST CDS_LMAN_SYM_OUTLINE -1150,1400,1150,-1400
J 0
(-3800 -2550);
DISPLAY 0.468085 (-3800 -2550);
PAINT GREEN (-3800 -2550);
DISPLAY INVISIBLE (-3800 -2550);
FORCEPROP 1 LAST PACK_TYPE ASIC2-GB1
J 0
(-3800 -2550);
DISPLAY 0.617021 (-3800 -2550);
PAINT GREEN (-3800 -2550);
DISPLAY INVISIBLE (-3800 -2550);
FORCEPROP 2 LAST SEC 3
J 0
(-4950 -1075);
DISPLAY 0.680851 (-4950 -1075);
PAINT MONO (-4950 -1075);
DISPLAY INVISIBLE (-4950 -1075);
FORCEPROP 2 LAST SEC_TYPE ASIC2-GB1
J 0
(-4950 -1075);
DISPLAY 1.021277 (-4950 -1075);
PAINT ORANGE (-4950 -1075);
DISPLAY INVISIBLE (-4950 -1075);
FORCEADD 200R2F-L1-GP..1
R 1
(-1625 -3200);
FORCEPROP 2 LAST RATED 1/16W
J 0
(-1800 -3425);
DISPLAY 0.638298 (-1800 -3425);
PAINT GREEN (-1800 -3425);
FORCEPROP 2 LAST ATTRIBUTE 200 OHM
J 0
(-1800 -3325);
DISPLAY 0.638298 (-1800 -3325);
PAINT GREEN (-1800 -3325);
FORCEPROP 2 LAST TOLERANCE 1%
J 0
(-1800 -3375);
DISPLAY 0.638298 (-1800 -3375);
PAINT GREEN (-1800 -3375);
FORCEPROP 2 LAST PACK_SIZE 0402
J 0
(-1600 -3325);
DISPLAY 0.638298 (-1600 -3325);
PAINT GREEN (-1600 -3325);
FORCEPROP 1 LAST VALUE 200R2F-L1-GP
J 0
(-1595 -3280);
DISPLAY 0.617021 (-1595 -3280);
PAINT GREEN (-1595 -3280);
FORCEPROP 1 LAST LOCATION R25W67
J 0
(-1805 -3280);
DISPLAY 0.617021 (-1805 -3280);
PAINT GREEN (-1805 -3280);
FORCEPROP 0 LAST GROUP AST2500
J 0
(-1600 -3375);
DISPLAY 0.638298 (-1600 -3375);
PAINT BROWN (-1600 -3375);
DISPLAY BOTH (-1600 -3375);
FORCEPROP 1 LAST CDS_LMAN_SYM_OUTLINE -50,75,50,-75
R 1
J 0
(-1625 -3200);
DISPLAY 0.468085 (-1625 -3200);
PAINT GREEN (-1625 -3200);
DISPLAY INVISIBLE (-1625 -3200);
FORCEPROP 1 LAST PATH I118
R 1
J 0
(-1625 -3200);
DISPLAY 0.617021 (-1625 -3200);
PAINT GREEN (-1625 -3200);
DISPLAY INVISIBLE (-1625 -3200);
FORCEPROP 2 LAST CDS_LIB w_hdl
R 1
J 0
(-1625 -3200);
PAINT MONO (-1625 -3200);
DISPLAY INVISIBLE (-1625 -3200);
FORCEPROP 1 LAST PART_NUMBER 64.20005.L0L
R 1
J 0
(-1625 -3200);
DISPLAY 0.617021 (-1625 -3200);
PAINT GREEN (-1625 -3200);
DISPLAY INVISIBLE (-1625 -3200);
FORCEPROP 1 LAST PACK_TYPE SMD-RG4
R 1
J 0
(-1625 -3200);
DISPLAY 0.617021 (-1625 -3200);
PAINT GREEN (-1625 -3200);
DISPLAY INVISIBLE (-1625 -3200);
FORCEADD RES..1
(-6450 -2300);
FORCEPROP 1 LAST TOLERANCE 5%
J 0
(-6450 -2250);
DISPLAY 0.617021 (-6450 -2250);
PAINT SKYBLUE (-6450 -2250);
FORCEPROP 1 LASTPIN (-6350 -2300) $PN 2
J 0
(-6388 -2288);
DISPLAY 0.787234 (-6388 -2288);
PAINT ORANGE (-6388 -2288);
FORCEPROP 1 LASTPIN (-6550 -2300) $PN 1
J 0
(-6538 -2288);
DISPLAY 0.787234 (-6538 -2288);
PAINT ORANGE (-6538 -2288);
FORCEPROP 1 LAST LOCATION R6W18
J 0
(-6750 -2300);
DISPLAY 0.617021 (-6750 -2300);
PAINT AQUA (-6750 -2300);
FORCEPROP 1 LAST VALUE 0.0
J 2
(-6500 -2250);
DISPLAY 0.617021 (-6500 -2250);
PAINT SKYBLUE (-6500 -2250);
FORCEPROP 1 LAST MATERIAL CHIP
J 0
(-6325 -2300);
DISPLAY 0.617021 (-6325 -2300);
PAINT SKYBLUE (-6325 -2300);
FORCEPROP 1 LAST WATTAGE 1/16W
J 0
(-6325 -2250);
DISPLAY 0.510638 (-6325 -2250);
PAINT SKYBLUE (-6325 -2250);
FORCEPROP 1 LAST PART_NUMBER G21497-005
J 0
(-6175 -2250);
DISPLAY 0.510638 (-6175 -2250);
PAINT BLUE (-6175 -2250);
FORCEPROP 1 LAST PACK_TYPE 0402
J 0
(-6200 -2300);
DISPLAY 0.617021 (-6200 -2300);
PAINT SKYBLUE (-6200 -2300);
FORCEPROP 0 LAST BOM_COST MIO_USB
J 0
(-6275 -2150);
DISPLAY 1.021277 (-6275 -2150);
PAINT ORANGE (-6275 -2150);
DISPLAY INVISIBLE (-6275 -2150);
FORCEPROP 0 LAST ROOM USB
J 0
(-6275 -2200);
DISPLAY 1.021277 (-6275 -2200);
PAINT ORANGE (-6275 -2200);
DISPLAY INVISIBLE (-6275 -2200);
FORCEPROP 1 LAST PATH I119
J 0
(-6500 -2150);
DISPLAY 0.978723 (-6500 -2150);
PAINT WHITE (-6500 -2150);
DISPLAY INVISIBLE (-6500 -2150);
FORCEPROP 2 LAST SEC_TYPE 0402
J 0
(-6500 -2100);
DISPLAY 1.021277 (-6500 -2100);
PAINT ORANGE (-6500 -2100);
DISPLAY INVISIBLE (-6500 -2100);
FORCEPROP 0 LAST SEC 1
J 0
(-6925 -2175);
DISPLAY 0.680851 (-6925 -2175);
PAINT MONO (-6925 -2175);
DISPLAY INVISIBLE (-6925 -2175);
FORCEPROP 2 LAST CDS_LIB mstr_discrete
J 0
(-6450 -2300);
PAINT MONO (-6450 -2300);
DISPLAY INVISIBLE (-6450 -2300);
FORCEADD OFFPAGE..1
(-5100 -250);
FORCEPROP 2 LAST $XR0 101 
J 0
(-5352 -250);
DISPLAY 0.638298 (-5352 -250);
PAINT MONO (-5352 -250);
FORCEPROP 1 LAST COMMENT_BODY TRUE
J 0
(-4975 -350);
DISPLAY 0.872340 (-4975 -350);
PAINT GREEN (-4975 -350);
DISPLAY INVISIBLE (-4975 -350);
FORCEPROP 1 LAST OFFPAGE TRUE
J 0
(-4775 -375);
DISPLAY 0.872340 (-4775 -375);
PAINT GREEN (-4775 -375);
DISPLAY INVISIBLE (-4775 -375);
FORCEPROP 2 LAST CDS_LIB mstr_standard
J 0
(-5100 -250);
PAINT ORANGE (-5100 -250);
DISPLAY INVISIBLE (-5100 -250);
FORCEPROP 2 LAST PATH I12
J 0
(-5350 -200);
DISPLAY 1.021277 (-5350 -200);
PAINT ORANGE (-5350 -200);
DISPLAY INVISIBLE (-5350 -200);
FORCEADD RES..1
(-6450 -2350);
FORCEPROP 1 LAST TOLERANCE 5%
J 0
(-6450 -2400);
DISPLAY 0.617021 (-6450 -2400);
PAINT SKYBLUE (-6450 -2400);
FORCEPROP 1 LAST PACK_TYPE 0402
J 0
(-6200 -2350);
DISPLAY 0.617021 (-6200 -2350);
PAINT SKYBLUE (-6200 -2350);
FORCEPROP 1 LAST LOCATION R6W17
J 0
(-6750 -2350);
DISPLAY 0.617021 (-6750 -2350);
PAINT AQUA (-6750 -2350);
FORCEPROP 1 LASTPIN (-6550 -2350) $PN 1
J 0
(-6538 -2338);
DISPLAY 0.787234 (-6538 -2338);
PAINT ORANGE (-6538 -2338);
FORCEPROP 1 LASTPIN (-6350 -2350) $PN 2
J 0
(-6388 -2338);
DISPLAY 0.787234 (-6388 -2338);
PAINT ORANGE (-6388 -2338);
FORCEPROP 1 LAST VALUE 0.0
J 2
(-6500 -2400);
DISPLAY 0.617021 (-6500 -2400);
PAINT SKYBLUE (-6500 -2400);
FORCEPROP 1 LAST MATERIAL CHIP
J 0
(-6325 -2350);
DISPLAY 0.617021 (-6325 -2350);
PAINT SKYBLUE (-6325 -2350);
FORCEPROP 1 LAST WATTAGE 1/16W
J 0
(-6325 -2400);
DISPLAY 0.510638 (-6325 -2400);
PAINT SKYBLUE (-6325 -2400);
FORCEPROP 1 LAST PART_NUMBER G21497-005
J 0
(-6175 -2400);
DISPLAY 0.510638 (-6175 -2400);
PAINT BLUE (-6175 -2400);
FORCEPROP 0 LAST ROOM USB
J 0
(-6275 -2250);
DISPLAY 1.021277 (-6275 -2250);
PAINT ORANGE (-6275 -2250);
DISPLAY INVISIBLE (-6275 -2250);
FORCEPROP 0 LAST BOM_COST MIO_USB
J 0
(-6275 -2200);
DISPLAY 1.021277 (-6275 -2200);
PAINT ORANGE (-6275 -2200);
DISPLAY INVISIBLE (-6275 -2200);
FORCEPROP 1 LAST PATH I120
J 0
(-6500 -2200);
DISPLAY 0.978723 (-6500 -2200);
PAINT WHITE (-6500 -2200);
DISPLAY INVISIBLE (-6500 -2200);
FORCEPROP 2 LAST SEC_TYPE 0402
J 0
(-6500 -2150);
DISPLAY 1.021277 (-6500 -2150);
PAINT ORANGE (-6500 -2150);
DISPLAY INVISIBLE (-6500 -2150);
FORCEPROP 0 LAST SEC 1
J 0
(-6475 -2275);
DISPLAY 0.680851 (-6475 -2275);
PAINT MONO (-6475 -2275);
DISPLAY INVISIBLE (-6475 -2275);
FORCEPROP 2 LAST CDS_LIB mstr_discrete
J 0
(-6450 -2350);
PAINT MONO (-6450 -2350);
DISPLAY INVISIBLE (-6450 -2350);
FORCEADD OFFPAGE..3
R 2
(-7750 -2300);
FORCEPROP 2 LAST $XR1 247 
J 0
(-8150 -2300);
DISPLAY 0.638298 (-8150 -2300);
PAINT MONO (-8150 -2300);
FORCEPROP 2 LAST $XR0 176 
J 0
(-8030 -2300);
DISPLAY 0.638298 (-8030 -2300);
PAINT MONO (-8030 -2300);
FORCEPROP 2 LAST CDS_LIB mstr_standard
J 0
(-7750 -2300);
PAINT MONO (-7750 -2300);
DISPLAY INVISIBLE (-7750 -2300);
FORCEPROP 2 LAST BOM_COST SM_CONTROLLER
J 2
(-8225 -2250);
PAINT MONO (-8225 -2250);
DISPLAY INVISIBLE (-8225 -2250);
FORCEPROP 2 LAST ROOM BMC
J 2
(-8225 -2250);
PAINT MONO (-8225 -2250);
DISPLAY INVISIBLE (-8225 -2250);
FORCEPROP 2 LAST PATH I121
J 0
(-8025 -2250);
DISPLAY 1.021277 (-8025 -2250);
PAINT ORANGE (-8025 -2250);
DISPLAY INVISIBLE (-8025 -2250);
FORCEPROP 1 LAST OFFPAGE TRUE
J 2
(-8075 -2425);
PAINT GREEN (-8075 -2425);
DISPLAY INVISIBLE (-8075 -2425);
FORCEPROP 1 LAST COMMENT_BODY TRUE
J 2
(-7700 -2400);
DISPLAY 1.170213 (-7700 -2400);
PAINT GREEN (-7700 -2400);
DISPLAY INVISIBLE (-7700 -2400);
FORCEADD OFFPAGE..5
(-7750 -2350);
FORCEPROP 2 LAST $XR1 247 
J 0
(-8155 -2350);
DISPLAY 0.638298 (-8155 -2350);
PAINT MONO (-8155 -2350);
FORCEPROP 2 LAST $XR0 176 
J 0
(-8035 -2350);
DISPLAY 0.638298 (-8035 -2350);
PAINT MONO (-8035 -2350);
FORCEPROP 2 LAST CDS_LIB mstr_standard
J 0
(-7750 -2350);
PAINT MONO (-7750 -2350);
DISPLAY INVISIBLE (-7750 -2350);
FORCEPROP 2 LAST PATH I122
J 0
(-8000 -2300);
DISPLAY 1.021277 (-8000 -2300);
PAINT ORANGE (-8000 -2300);
DISPLAY INVISIBLE (-8000 -2300);
FORCEPROP 1 LAST OFFPAGE TRUE
J 0
(-7425 -2475);
DISPLAY 0.872340 (-7425 -2475);
PAINT GREEN (-7425 -2475);
DISPLAY INVISIBLE (-7425 -2475);
FORCEPROP 1 LAST COMMENT_BODY TRUE
J 0
(-7650 -2425);
DISPLAY 0.872340 (-7650 -2425);
PAINT GREEN (-7650 -2425);
DISPLAY INVISIBLE (-7650 -2425);
FORCEADD OFFPAGE..2
R 2
(-6150 -2050);
FORCEPROP 2 LAST $XR1 182 
J 0
(-6555 -2050);
DISPLAY 0.638298 (-6555 -2050);
PAINT MONO (-6555 -2050);
FORCEPROP 2 LAST $XR0 163 
J 0
(-6435 -2050);
DISPLAY 0.638298 (-6435 -2050);
PAINT MONO (-6435 -2050);
FORCEPROP 2 LAST CDS_LIB mstr_standard
J 0
(-6150 -2050);
PAINT MONO (-6150 -2050);
DISPLAY INVISIBLE (-6150 -2050);
FORCEPROP 2 LAST PATH I123
J 2
(-6350 -2000);
DISPLAY 1.021277 (-6350 -2000);
PAINT ORANGE (-6350 -2000);
DISPLAY INVISIBLE (-6350 -2000);
FORCEPROP 1 LAST COMMENT_BODY TRUE
J 2
(-6105 -2145);
DISPLAY 0.872340 (-6105 -2145);
PAINT GREEN (-6105 -2145);
DISPLAY INVISIBLE (-6105 -2145);
FORCEPROP 1 LAST OFFPAGE TRUE
J 2
(-6475 -2175);
DISPLAY 0.872340 (-6475 -2175);
PAINT GREEN (-6475 -2175);
DISPLAY INVISIBLE (-6475 -2175);
FORCEADD OFFPAGE..3
R 2
(-6150 -2000);
FORCEPROP 2 LAST $XR1 182 
J 0
(-6550 -2000);
DISPLAY 0.638298 (-6550 -2000);
PAINT MONO (-6550 -2000);
FORCEPROP 2 LAST $XR0 163 
J 0
(-6430 -2000);
DISPLAY 0.638298 (-6430 -2000);
PAINT MONO (-6430 -2000);
FORCEPROP 2 LAST CDS_LIB mstr_standard
J 0
(-6150 -2000);
PAINT MONO (-6150 -2000);
DISPLAY INVISIBLE (-6150 -2000);
FORCEPROP 1 LAST OFFPAGE TRUE
J 2
(-6475 -2125);
DISPLAY 0.872340 (-6475 -2125);
PAINT GREEN (-6475 -2125);
DISPLAY INVISIBLE (-6475 -2125);
FORCEPROP 1 LAST COMMENT_BODY TRUE
J 2
(-6100 -2100);
DISPLAY 0.872340 (-6100 -2100);
PAINT GREEN (-6100 -2100);
DISPLAY INVISIBLE (-6100 -2100);
FORCEPROP 2 LAST PATH I124
J 2
(-6375 -1950);
DISPLAY 1.021277 (-6375 -1950);
PAINT ORANGE (-6375 -1950);
DISPLAY INVISIBLE (-6375 -1950);
FORCEADD OFFPAGE..1
(-6150 -2550);
FORCEPROP 2 LAST $XR2 119 
J 0
(-6672 -2550);
DISPLAY 0.638298 (-6672 -2550);
PAINT MONO (-6672 -2550);
FORCEPROP 2 LAST $XR1 157 
J 0
(-6552 -2550);
DISPLAY 0.638298 (-6552 -2550);
PAINT MONO (-6552 -2550);
FORCEPROP 2 LAST $XR0 108 
J 0
(-6432 -2550);
DISPLAY 0.638298 (-6432 -2550);
PAINT MONO (-6432 -2550);
FORCEPROP 2 LAST CDS_LIB mstr_standard
J 0
(-6150 -2550);
PAINT MONO (-6150 -2550);
DISPLAY INVISIBLE (-6150 -2550);
FORCEPROP 2 LAST BOM_COST SM_CONTROLLER
J 0
(-5700 -2500);
PAINT MONO (-5700 -2500);
DISPLAY INVISIBLE (-5700 -2500);
FORCEPROP 2 LAST ROOM BMC
J 0
(-6400 -2475);
DISPLAY 1.361702 (-6400 -2475);
PAINT ORANGE (-6400 -2475);
DISPLAY INVISIBLE (-6400 -2475);
FORCEPROP 1 LAST OFFPAGE TRUE
J 0
(-5825 -2675);
DISPLAY 0.872340 (-5825 -2675);
PAINT GREEN (-5825 -2675);
DISPLAY INVISIBLE (-5825 -2675);
FORCEPROP 1 LAST COMMENT_BODY TRUE
J 0
(-6025 -2650);
DISPLAY 0.872340 (-6025 -2650);
PAINT GREEN (-6025 -2650);
DISPLAY INVISIBLE (-6025 -2650);
FORCEPROP 2 LAST PATH I128
J 0
(-6400 -2500);
DISPLAY 1.021277 (-6400 -2500);
PAINT ORANGE (-6400 -2500);
DISPLAY INVISIBLE (-6400 -2500);
FORCEADD GND..1
(-5275 -875);
FORCEPROP 3 LASTPIN (-5275 -825) SIG_NAME GND\g
J 0
(-5265 -815);
DISPLAY 0.659574 (-5265 -815);
PAINT MONO (-5265 -815);
DISPLAY INVISIBLE (-5265 -815);
FORCEPROP 1 LAST HDL_POWER GND
J 0
(-5275 -725);
DISPLAY 0.872340 (-5275 -725);
PAINT GREEN (-5275 -725);
DISPLAY INVISIBLE (-5275 -725);
FORCEPROP 1 LAST BODY_TYPE PLUMBING
J 0
(-5320 -918);
DISPLAY 0.340426 (-5320 -918);
PAINT GREEN (-5320 -918);
DISPLAY INVISIBLE (-5320 -918);
FORCEPROP 1 LAST VOLTAGE 0.0V
J 0
(-5320 -918);
DISPLAY 0.340426 (-5320 -918);
PAINT SKYBLUE (-5320 -918);
DISPLAY INVISIBLE (-5320 -918);
FORCEPROP 1 LAST SIZE 1B
J 0
(-5200 -925);
DISPLAY 0.872340 (-5200 -925);
PAINT AQUA (-5200 -925);
DISPLAY INVISIBLE (-5200 -925);
FORCEPROP 2 LAST CDS_LIB mstr_symbols
J 0
(-5275 -875);
PAINT ORANGE (-5275 -875);
DISPLAY INVISIBLE (-5275 -875);
FORCEPROP 1 LAST PATH I13
J 0
(-5200 -875);
DISPLAY 0.872340 (-5200 -875);
PAINT AQUA (-5200 -875);
DISPLAY INVISIBLE (-5200 -875);
FORCEADD RES..1
(-6450 -2950);
FORCEPROP 1 LASTPIN (-6350 -2950) $PN 2
J 0
(-6388 -2938);
DISPLAY 0.617021 (-6388 -2938);
PAINT ORANGE (-6388 -2938);
FORCEPROP 1 LAST TOLERANCE 1.0%
J 0
(-6425 -3000);
DISPLAY 0.617021 (-6425 -3000);
PAINT SKYBLUE (-6425 -3000);
FORCEPROP 1 LAST WATTAGE 1/16W
J 2
(-6175 -3000);
DISPLAY 0.617021 (-6175 -3000);
PAINT SKYBLUE (-6175 -3000);
FORCEPROP 1 LAST MATERIAL CHIP
J 0
(-6325 -2950);
DISPLAY 0.617021 (-6325 -2950);
PAINT SKYBLUE (-6325 -2950);
FORCEPROP 1 LAST PACK_TYPE 0402
J 0
(-6200 -2950);
DISPLAY 0.617021 (-6200 -2950);
PAINT SKYBLUE (-6200 -2950);
FORCEPROP 1 LAST VALUE 22.1
J 2
(-6450 -3000);
DISPLAY 0.617021 (-6450 -3000);
PAINT SKYBLUE (-6450 -3000);
FORCEPROP 1 LAST LOCATION R2T41
J 0
(-6750 -2950);
DISPLAY 0.617021 (-6750 -2950);
PAINT AQUA (-6750 -2950);
FORCEPROP 1 LASTPIN (-6550 -2950) $PN 1
J 0
(-6538 -2938);
DISPLAY 0.617021 (-6538 -2938);
PAINT ORANGE (-6538 -2938);
FORCEPROP 1 LAST PART_NUMBER G21796-250
J 0
(-6775 -3000);
DISPLAY 0.617021 (-6775 -3000);
PAINT BLUE (-6775 -3000);
FORCEPROP 2 LAST CDS_LOCATION R2T41
J 0
(-6500 -2925);
DISPLAY 0.617021 (-6500 -2925);
PAINT AQUA (-6500 -2925);
DISPLAY INVISIBLE (-6500 -2925);
FORCEPROP 2 LAST CDS_LIB mstr_discrete
J 0
(-6450 -2950);
PAINT ORANGE (-6450 -2950);
DISPLAY INVISIBLE (-6450 -2950);
FORCEPROP 0 LAST ROOM BMC
J 0
(-6500 -2800);
DISPLAY 0.617021 (-6500 -2800);
PAINT ORANGE (-6500 -2800);
DISPLAY INVISIBLE (-6500 -2800);
FORCEPROP 0 LAST BOM_COST SM_CONTROLLER
J 0
(-6500 -2700);
DISPLAY 1.021277 (-6500 -2700);
PAINT ORANGE (-6500 -2700);
DISPLAY INVISIBLE (-6500 -2700);
FORCEPROP 2 LAST SEC_TYPE 0402
J 0
(-6500 -2750);
DISPLAY 1.021277 (-6500 -2750);
PAINT ORANGE (-6500 -2750);
DISPLAY INVISIBLE (-6500 -2750);
FORCEPROP 2 LAST SEC 1
J 0
(-6500 -2750);
PAINT MONO (-6500 -2750);
DISPLAY INVISIBLE (-6500 -2750);
FORCEPROP 0 LAST CDS_SEC 1
J 0
(-6500 -2875);
PAINT MONO (-6500 -2875);
DISPLAY INVISIBLE (-6500 -2875);
FORCEPROP 1 LAST PATH I136
J 0
(-6500 -2800);
DISPLAY 0.978723 (-6500 -2800);
PAINT WHITE (-6500 -2800);
DISPLAY INVISIBLE (-6500 -2800);
FORCEADD OFFPAGE..5
(-7750 -2950);
FORCEPROP 2 LAST $XR2 170 
J 0
(-8245 -2950);
DISPLAY 0.638298 (-8245 -2950);
PAINT MONO (-8245 -2950);
FORCEPROP 2 LAST $XR1 120 
J 0
(-8125 -2950);
DISPLAY 0.638298 (-8125 -2950);
PAINT MONO (-8125 -2950);
FORCEPROP 2 LAST $XR0 119 
J 0
(-8005 -2950);
DISPLAY 0.638298 (-8005 -2950);
PAINT MONO (-8005 -2950);
FORCEPROP 2 LAST PATH I137
J 0
(-8000 -2900);
DISPLAY 1.021277 (-8000 -2900);
PAINT ORANGE (-8000 -2900);
DISPLAY INVISIBLE (-8000 -2900);
FORCEPROP 1 LAST COMMENT_BODY TRUE
J 0
(-7650 -3025);
DISPLAY 0.872340 (-7650 -3025);
PAINT GREEN (-7650 -3025);
DISPLAY INVISIBLE (-7650 -3025);
FORCEPROP 1 LAST OFFPAGE TRUE
J 0
(-7425 -3075);
DISPLAY 0.872340 (-7425 -3075);
PAINT GREEN (-7425 -3075);
DISPLAY INVISIBLE (-7425 -3075);
FORCEPROP 2 LAST CDS_LIB mstr_standard
J 0
(-7750 -2950);
PAINT ORANGE (-7750 -2950);
DISPLAY INVISIBLE (-7750 -2950);
FORCEADD OFFPAGE..5
R 2
(-1250 -1450);
FORCEPROP 2 LAST $XR1 119 
J 0
(-941 -1450);
DISPLAY 0.638298 (-941 -1450);
PAINT MONO (-941 -1450);
FORCEPROP 2 LAST $XR0 191 
J 0
(-1061 -1450);
DISPLAY 0.638298 (-1061 -1450);
PAINT MONO (-1061 -1450);
FORCEPROP 2 LAST CDS_LIB mstr_standard
J 2
(-1250 -1450);
PAINT MONO (-1250 -1450);
DISPLAY INVISIBLE (-1250 -1450);
FORCEPROP 1 LAST OFFPAGE TRUE
J 2
(-1575 -1575);
DISPLAY 0.872340 (-1575 -1575);
PAINT GREEN (-1575 -1575);
DISPLAY INVISIBLE (-1575 -1575);
FORCEPROP 1 LAST COMMENT_BODY TRUE
J 2
(-1350 -1525);
DISPLAY 0.872340 (-1350 -1525);
PAINT GREEN (-1350 -1525);
DISPLAY INVISIBLE (-1350 -1525);
FORCEPROP 2 LAST PATH I138
J 2
(-775 -1400);
DISPLAY 1.021277 (-775 -1400);
PAINT ORANGE (-775 -1400);
DISPLAY INVISIBLE (-775 -1400);
FORCEADD OFFPAGE..2
R 2
(-6150 -3100);
FORCEPROP 2 LAST $XR2 190 
J 0
(-6645 -3100);
DISPLAY 0.638298 (-6645 -3100);
PAINT MONO (-6645 -3100);
FORCEPROP 2 LAST $XR1 157 
J 0
(-6525 -3100);
DISPLAY 0.638298 (-6525 -3100);
PAINT MONO (-6525 -3100);
FORCEPROP 2 LAST $XR0 119 
J 0
(-6405 -3100);
DISPLAY 0.638298 (-6405 -3100);
PAINT MONO (-6405 -3100);
FORCEPROP 1 LAST COMMENT_BODY TRUE
J 2
(-6105 -3195);
DISPLAY 0.872340 (-6105 -3195);
PAINT GREEN (-6105 -3195);
DISPLAY INVISIBLE (-6105 -3195);
FORCEPROP 1 LAST OFFPAGE TRUE
J 2
(-6475 -3225);
DISPLAY 0.872340 (-6475 -3225);
PAINT GREEN (-6475 -3225);
DISPLAY INVISIBLE (-6475 -3225);
FORCEPROP 2 LAST CDS_LIB mstr_standard
J 2
(-6150 -3100);
PAINT MONO (-6150 -3100);
DISPLAY INVISIBLE (-6150 -3100);
FORCEPROP 2 LAST PATH I139
J 2
(-6600 -3050);
DISPLAY 1.021277 (-6600 -3050);
PAINT ORANGE (-6600 -3050);
DISPLAY INVISIBLE (-6600 -3050);
FORCEADD RES..2
(-7000 -475);
FORCEPROP 1 LAST PACK_TYPE 0402
J 0
(-6960 -650);
DISPLAY 0.617021 (-6960 -650);
PAINT SKYBLUE (-6960 -650);
FORCEPROP 1 LAST MATERIAL CHIP
J 0
(-6960 -550);
DISPLAY 0.617021 (-6960 -550);
PAINT SKYBLUE (-6960 -550);
FORCEPROP 1 LAST TOLERANCE 1%
J 0
(-6955 -450);
DISPLAY 0.617021 (-6955 -450);
PAINT SKYBLUE (-6955 -450);
FORCEPROP 1 LASTPIN (-7000 -575) $PN 2
J 0
(-6995 -565);
DISPLAY 0.617021 (-6995 -565);
PAINT ORANGE (-6995 -565);
FORCEPROP 1 LASTPIN (-7000 -375) $PN 1
J 0
(-6995 -413);
DISPLAY 0.617021 (-6995 -413);
PAINT ORANGE (-6995 -413);
FORCEPROP 1 LAST VALUE 10.0K
J 0
(-6955 -400);
DISPLAY 0.617021 (-6955 -400);
PAINT SKYBLUE (-6955 -400);
FORCEPROP 1 LAST LOCATION R9F61
J 0
(-6955 -350);
DISPLAY 0.617021 (-6955 -350);
PAINT AQUA (-6955 -350);
FORCEPROP 1 LAST WATTAGE 1/16W
J 0
(-6960 -500);
DISPLAY 0.617021 (-6960 -500);
PAINT SKYBLUE (-6960 -500);
FORCEPROP 1 LAST PART_NUMBER G21796-016
J 0
(-6960 -600);
DISPLAY 0.617021 (-6960 -600);
PAINT BLUE (-6960 -600);
FORCEPROP 0 LAST CDS_SEC 1
J 0
(-6950 -300);
PAINT MONO (-6950 -300);
DISPLAY INVISIBLE (-6950 -300);
FORCEPROP 0 LAST CDS_LOCATION R9F61
J 0
(-6950 -300);
PAINT MONO (-6950 -300);
DISPLAY INVISIBLE (-6950 -300);
FORCEPROP 2 LAST SEC 1
J 0
(-6950 -250);
DISPLAY 0.680851 (-6950 -250);
PAINT MONO (-6950 -250);
DISPLAY INVISIBLE (-6950 -250);
FORCEPROP 0 LAST BOM_COST SM_CONTROLLER
J 0
(-6950 -150);
DISPLAY 1.021277 (-6950 -150);
PAINT ORANGE (-6950 -150);
DISPLAY INVISIBLE (-6950 -150);
FORCEPROP 2 LAST SEC_TYPE 0402
J 0
(-6950 -250);
DISPLAY 1.021277 (-6950 -250);
PAINT ORANGE (-6950 -250);
DISPLAY INVISIBLE (-6950 -250);
FORCEPROP 0 LAST ROOM BMC
J 0
(-6950 -250);
DISPLAY 1.021277 (-6950 -250);
PAINT ORANGE (-6950 -250);
DISPLAY INVISIBLE (-6950 -250);
FORCEPROP 2 LAST CDS_LIB mstr_discrete
J 0
(-7000 -475);
PAINT ORANGE (-7000 -475);
DISPLAY INVISIBLE (-7000 -475);
FORCEPROP 1 LAST PATH I14
J 0
(-6950 -300);
DISPLAY 0.978723 (-6950 -300);
PAINT WHITE (-6950 -300);
DISPLAY INVISIBLE (-6950 -300);
FORCEADD OFFPAGE..4
(-1250 -1400);
FORCEPROP 2 LAST $XR1 120 
J 0
(-944 -1400);
DISPLAY 0.638298 (-944 -1400);
PAINT MONO (-944 -1400);
FORCEPROP 2 LAST $XR0 191 
J 0
(-1064 -1400);
DISPLAY 0.638298 (-1064 -1400);
PAINT MONO (-1064 -1400);
FORCEPROP 2 LAST PATH I140
J 0
(-925 -1350);
DISPLAY 1.021277 (-925 -1350);
PAINT ORANGE (-925 -1350);
DISPLAY INVISIBLE (-925 -1350);
FORCEPROP 2 LAST CDS_LIB mstr_standard
J 0
(-1250 -1400);
PAINT MONO (-1250 -1400);
DISPLAY INVISIBLE (-1250 -1400);
FORCEPROP 1 LAST OFFPAGE TRUE
J 0
(-925 -1525);
DISPLAY 0.872340 (-925 -1525);
PAINT GREEN (-925 -1525);
DISPLAY INVISIBLE (-925 -1525);
FORCEPROP 1 LAST COMMENT_BODY TRUE
J 0
(-1275 -1500);
DISPLAY 0.872340 (-1275 -1500);
PAINT GREEN (-1275 -1500);
DISPLAY INVISIBLE (-1275 -1500);
FORCEADD OFFPAGE..1
(-6150 -2600);
FORCEPROP 2 LAST $XR2 119 
J 0
(-6672 -2600);
DISPLAY 0.638298 (-6672 -2600);
PAINT MONO (-6672 -2600);
FORCEPROP 2 LAST $XR1 133 
J 0
(-6552 -2600);
DISPLAY 0.638298 (-6552 -2600);
PAINT MONO (-6552 -2600);
FORCEPROP 2 LAST $XR0 120 
J 0
(-6432 -2600);
DISPLAY 0.638298 (-6432 -2600);
PAINT MONO (-6432 -2600);
FORCEPROP 1 LAST COMMENT_BODY TRUE
J 0
(-6025 -2700);
DISPLAY 0.872340 (-6025 -2700);
PAINT GREEN (-6025 -2700);
DISPLAY INVISIBLE (-6025 -2700);
FORCEPROP 1 LAST OFFPAGE TRUE
J 0
(-5825 -2725);
DISPLAY 0.872340 (-5825 -2725);
PAINT GREEN (-5825 -2725);
DISPLAY INVISIBLE (-5825 -2725);
FORCEPROP 2 LAST ROOM BMC
J 0
(-6400 -2525);
DISPLAY 1.361702 (-6400 -2525);
PAINT ORANGE (-6400 -2525);
DISPLAY INVISIBLE (-6400 -2525);
FORCEPROP 2 LAST BOM_COST SM_CONTROLLER
J 0
(-5700 -2550);
PAINT MONO (-5700 -2550);
DISPLAY INVISIBLE (-5700 -2550);
FORCEPROP 2 LAST CDS_LIB mstr_standard
J 0
(-6150 -2600);
PAINT MONO (-6150 -2600);
DISPLAY INVISIBLE (-6150 -2600);
FORCEPROP 2 LAST PATH I143
J 0
(-6400 -2550);
DISPLAY 1.021277 (-6400 -2550);
PAINT ORANGE (-6400 -2550);
DISPLAY INVISIBLE (-6400 -2550);
FORCEADD OFFPAGE..1
(-6150 -2500);
FORCEPROP 2 LAST $XR3 119 
J 0
(-6792 -2500);
DISPLAY 0.638298 (-6792 -2500);
PAINT MONO (-6792 -2500);
FORCEPROP 2 LAST $XR2 186 
J 0
(-6672 -2500);
DISPLAY 0.638298 (-6672 -2500);
PAINT MONO (-6672 -2500);
FORCEPROP 2 LAST $XR1 185 
J 0
(-6552 -2500);
DISPLAY 0.638298 (-6552 -2500);
PAINT MONO (-6552 -2500);
FORCEPROP 2 LAST $XR0 157 
J 0
(-6432 -2500);
DISPLAY 0.638298 (-6432 -2500);
PAINT MONO (-6432 -2500);
FORCEPROP 1 LAST COMMENT_BODY TRUE
J 0
(-6025 -2600);
DISPLAY 0.872340 (-6025 -2600);
PAINT GREEN (-6025 -2600);
DISPLAY INVISIBLE (-6025 -2600);
FORCEPROP 1 LAST OFFPAGE TRUE
J 0
(-5825 -2625);
DISPLAY 0.872340 (-5825 -2625);
PAINT GREEN (-5825 -2625);
DISPLAY INVISIBLE (-5825 -2625);
FORCEPROP 2 LAST ROOM BMC
J 0
(-6400 -2425);
DISPLAY 1.361702 (-6400 -2425);
PAINT ORANGE (-6400 -2425);
DISPLAY INVISIBLE (-6400 -2425);
FORCEPROP 2 LAST BOM_COST SM_CONTROLLER
J 0
(-5700 -2450);
PAINT MONO (-5700 -2450);
DISPLAY INVISIBLE (-5700 -2450);
FORCEPROP 2 LAST CDS_LIB mstr_standard
J 0
(-6150 -2500);
PAINT MONO (-6150 -2500);
DISPLAY INVISIBLE (-6150 -2500);
FORCEPROP 2 LAST PATH I146
J 0
(-6400 -2450);
DISPLAY 1.021277 (-6400 -2450);
PAINT ORANGE (-6400 -2450);
DISPLAY INVISIBLE (-6400 -2450);
FORCEADD OFFPAGE..2
(-1250 -2500);
FORCEPROP 2 LAST $XR0 137 
J 0
(-1061 -2500);
DISPLAY 0.638298 (-1061 -2500);
PAINT MONO (-1061 -2500);
FORCEPROP 2 LAST PATH I147
J 0
(-1075 -2425);
DISPLAY 1.021277 (-1075 -2425);
PAINT ORANGE (-1075 -2425);
DISPLAY INVISIBLE (-1075 -2425);
FORCEPROP 1 LAST OFFPAGE TRUE
J 0
(-925 -2625);
DISPLAY 0.872340 (-925 -2625);
PAINT GREEN (-925 -2625);
DISPLAY INVISIBLE (-925 -2625);
FORCEPROP 1 LAST COMMENT_BODY TRUE
J 0
(-1295 -2595);
DISPLAY 0.872340 (-1295 -2595);
PAINT GREEN (-1295 -2595);
DISPLAY INVISIBLE (-1295 -2595);
FORCEPROP 2 LAST CDS_LIB mstr_standard
J 0
(-1250 -2500);
PAINT MONO (-1250 -2500);
DISPLAY INVISIBLE (-1250 -2500);
FORCEADD CAP_A..1
(-7500 -450);
FORCEPROP 1 LAST PART_NUMBER A36096-030
J 0
(-7450 -600);
DISPLAY 0.617021 (-7450 -600);
PAINT BLUE (-7450 -600);
FORCEPROP 1 LASTPIN (-7500 -550) $PN 2
J 0
(-7490 -570);
DISPLAY 0.617021 (-7490 -570);
PAINT ORANGE (-7490 -570);
FORCEPROP 1 LAST MATERIAL X7R
J 0
(-7450 -550);
DISPLAY 0.617021 (-7450 -550);
PAINT SKYBLUE (-7450 -550);
FORCEPROP 1 LAST PACK_TYPE 0402V
J 0
(-7450 -650);
DISPLAY 0.617021 (-7450 -650);
PAINT SKYBLUE (-7450 -650);
FORCEPROP 1 LASTPIN (-7500 -350) $PN 1
J 0
(-7490 -370);
DISPLAY 0.617021 (-7490 -370);
PAINT ORANGE (-7490 -370);
FORCEPROP 1 LAST VOLTAGE 16V
J 0
(-7450 -450);
DISPLAY 0.617021 (-7450 -450);
PAINT SKYBLUE (-7450 -450);
FORCEPROP 1 LAST TOLERANCE 10%
J 0
(-7450 -500);
DISPLAY 0.617021 (-7450 -500);
PAINT SKYBLUE (-7450 -500);
FORCEPROP 1 LAST VALUE 0.1UF
J 0
(-7450 -400);
DISPLAY 0.617021 (-7450 -400);
PAINT SKYBLUE (-7450 -400);
FORCEPROP 1 LAST LOCATION C9F23
J 0
(-7450 -350);
DISPLAY 0.617021 (-7450 -350);
PAINT AQUA (-7450 -350);
FORCEPROP 0 LAST CDS_LOCATION C9F23
J 0
(-7450 -300);
PAINT MONO (-7450 -300);
DISPLAY INVISIBLE (-7450 -300);
FORCEPROP 0 LAST BOM_COST SM_CONTROLLER
J 0
(-7450 -150);
DISPLAY 1.021277 (-7450 -150);
PAINT ORANGE (-7450 -150);
DISPLAY INVISIBLE (-7450 -150);
FORCEPROP 2 LAST SEC_TYPE 0402V
J 0
(-7450 -250);
DISPLAY 1.021277 (-7450 -250);
PAINT ORANGE (-7450 -250);
DISPLAY INVISIBLE (-7450 -250);
FORCEPROP 0 LAST ROOM BMC
J 0
(-7450 -250);
DISPLAY 1.021277 (-7450 -250);
PAINT ORANGE (-7450 -250);
DISPLAY INVISIBLE (-7450 -250);
FORCEPROP 2 LAST CDS_SEC 1
J 0
(-7450 -300);
PAINT ORANGE (-7450 -300);
DISPLAY INVISIBLE (-7450 -300);
FORCEPROP 2 LAST SEC 1
J 0
(-7450 -300);
DISPLAY 0.680851 (-7450 -300);
PAINT MONO (-7450 -300);
DISPLAY INVISIBLE (-7450 -300);
FORCEPROP 2 LAST CDS_LIB dev_discrete
J 0
(-7500 -450);
PAINT ORANGE (-7500 -450);
DISPLAY INVISIBLE (-7500 -450);
FORCEPROP 1 LAST PATH I15
J 0
(-7450 -300);
DISPLAY 0.978723 (-7450 -300);
PAINT WHITE (-7450 -300);
DISPLAY INVISIBLE (-7450 -300);
FORCEADD OFFPAGE..3
R 2
(-7750 -2150);
FORCEPROP 2 LAST $XR0 248 
J 0
(-8030 -2150);
DISPLAY 0.638298 (-8030 -2150);
PAINT MONO (-8030 -2150);
FORCEPROP 1 LAST OFFPAGE TRUE
J 2
(-8075 -2275);
DISPLAY 0.872340 (-8075 -2275);
PAINT GREEN (-8075 -2275);
DISPLAY INVISIBLE (-8075 -2275);
FORCEPROP 1 LAST COMMENT_BODY TRUE
J 2
(-7700 -2250);
DISPLAY 0.872340 (-7700 -2250);
PAINT GREEN (-7700 -2250);
DISPLAY INVISIBLE (-7700 -2250);
FORCEPROP 2 LAST PATH I154
J 0
(-8025 -2100);
DISPLAY 1.021277 (-8025 -2100);
PAINT ORANGE (-8025 -2100);
DISPLAY INVISIBLE (-8025 -2100);
FORCEPROP 2 LAST CDS_LIB mstr_standard
J 0
(-7750 -2150);
PAINT MONO (-7750 -2150);
DISPLAY INVISIBLE (-7750 -2150);
FORCEADD OFFPAGE..1
(-7750 -2200);
FORCEPROP 2 LAST $XR0 248 
J 0
(-8032 -2200);
DISPLAY 0.638298 (-8032 -2200);
PAINT MONO (-8032 -2200);
FORCEPROP 2 LAST BOM_COST SM_CONTROLLER
J 0
(-7300 -2150);
PAINT MONO (-7300 -2150);
DISPLAY INVISIBLE (-7300 -2150);
FORCEPROP 2 LAST ROOM BMC
J 0
(-8000 -2125);
DISPLAY 1.361702 (-8000 -2125);
PAINT ORANGE (-8000 -2125);
DISPLAY INVISIBLE (-8000 -2125);
FORCEPROP 1 LAST OFFPAGE TRUE
J 0
(-7425 -2325);
DISPLAY 0.872340 (-7425 -2325);
PAINT GREEN (-7425 -2325);
DISPLAY INVISIBLE (-7425 -2325);
FORCEPROP 1 LAST COMMENT_BODY TRUE
J 0
(-7625 -2300);
DISPLAY 0.872340 (-7625 -2300);
PAINT GREEN (-7625 -2300);
DISPLAY INVISIBLE (-7625 -2300);
FORCEPROP 2 LAST PATH I155
J 0
(-8025 -2150);
DISPLAY 1.021277 (-8025 -2150);
PAINT ORANGE (-8025 -2150);
DISPLAY INVISIBLE (-8025 -2150);
FORCEPROP 2 LAST CDS_LIB mstr_standard
J 0
(-7750 -2200);
PAINT MONO (-7750 -2200);
DISPLAY INVISIBLE (-7750 -2200);
FORCEADD CAP_A..1
R 1
(-1650 -3550);
FORCEPROP 0 LAST GROUP AST2500
J 0
(-1600 -3775);
DISPLAY 0.638298 (-1600 -3775);
PAINT BROWN (-1600 -3775);
DISPLAY BOTH (-1600 -3775);
FORCEPROP 1 LAST PACK_TYPE 0402V
J 0
(-1600 -3725);
DISPLAY 0.617021 (-1600 -3725);
PAINT SKYBLUE (-1600 -3725);
FORCEPROP 1 LAST MATERIAL X7R
J 0
(-1600 -3625);
DISPLAY 0.617021 (-1600 -3625);
PAINT SKYBLUE (-1600 -3625);
FORCEPROP 1 LAST PART_NUMBER A36096-030
J 0
(-1600 -3675);
DISPLAY 0.617021 (-1600 -3675);
PAINT BLUE (-1600 -3675);
FORCEPROP 1 LAST LOCATION C25W20
J 0
(-1800 -3625);
DISPLAY 0.617021 (-1800 -3625);
PAINT AQUA (-1800 -3625);
FORCEPROP 1 LAST VOLTAGE 16V
J 0
(-1800 -3775);
DISPLAY 0.617021 (-1800 -3775);
PAINT SKYBLUE (-1800 -3775);
FORCEPROP 1 LAST TOLERANCE 10%
J 0
(-1800 -3725);
DISPLAY 0.617021 (-1800 -3725);
PAINT SKYBLUE (-1800 -3725);
FORCEPROP 1 LAST VALUE 0.1UF
J 0
(-1800 -3675);
DISPLAY 0.617021 (-1800 -3675);
PAINT SKYBLUE (-1800 -3675);
FORCEPROP 1 LASTPIN (-1750 -3550) $PN 1
J 0
(-1780 -3540);
DISPLAY 0.617021 (-1780 -3540);
PAINT MONO (-1780 -3540);
FORCEPROP 1 LASTPIN (-1550 -3550) $PN 2
J 0
(-1530 -3540);
DISPLAY 0.617021 (-1530 -3540);
PAINT MONO (-1530 -3540);
FORCEPROP 2 LAST CDS_LOCATION C25W20
R 1
J 0
(-1750 -3500);
DISPLAY 0.617021 (-1750 -3500);
PAINT AQUA (-1750 -3500);
DISPLAY INVISIBLE (-1750 -3500);
FORCEPROP 2 LAST SEC 1
R 1
J 0
(-1850 -3500);
DISPLAY 0.936170 (-1850 -3500);
PAINT MONO (-1850 -3500);
DISPLAY INVISIBLE (-1850 -3500);
FORCEPROP 2 LAST SEC_TYPE 0402V
R 1
J 0
(-1850 -3500);
PAINT MONO (-1850 -3500);
DISPLAY INVISIBLE (-1850 -3500);
FORCEPROP 2 LAST CDS_SEC 1
R 1
J 0
(-1800 -3500);
PAINT ORANGE (-1800 -3500);
DISPLAY INVISIBLE (-1800 -3500);
FORCEPROP 2 LAST CDS_LIB dev_discrete
R 1
J 0
(-1650 -3550);
PAINT ORANGE (-1650 -3550);
DISPLAY INVISIBLE (-1650 -3550);
FORCEPROP 2 LAST BOM_COST PROC_SIDEBAND
R 1
J 0
(-1650 -3550);
PAINT MONO (-1650 -3550);
DISPLAY INVISIBLE (-1650 -3550);
FORCEPROP 2 LAST ROOM PROC_SIDEBAND
R 1
J 0
(-1400 -3500);
DISPLAY 0.978723 (-1400 -3500);
PAINT ORANGE (-1400 -3500);
DISPLAY INVISIBLE (-1400 -3500);
FORCEPROP 1 LAST PATH I158
R 1
J 0
(-1800 -3500);
DISPLAY 0.978723 (-1800 -3500);
PAINT WHITE (-1800 -3500);
DISPLAY INVISIBLE (-1800 -3500);
FORCEADD CAP_A..1
R 1
(-1650 -3900);
FORCEPROP 1 LAST VALUE 0.1UF
J 0
(-1800 -4025);
DISPLAY 0.617021 (-1800 -4025);
PAINT SKYBLUE (-1800 -4025);
FORCEPROP 1 LAST TOLERANCE 10%
J 0
(-1800 -4075);
DISPLAY 0.617021 (-1800 -4075);
PAINT SKYBLUE (-1800 -4075);
FORCEPROP 1 LAST VOLTAGE 16V
J 0
(-1800 -4125);
DISPLAY 0.617021 (-1800 -4125);
PAINT SKYBLUE (-1800 -4125);
FORCEPROP 1 LASTPIN (-1750 -3900) $PN 1
J 0
(-1780 -3890);
DISPLAY 0.617021 (-1780 -3890);
PAINT MONO (-1780 -3890);
FORCEPROP 1 LASTPIN (-1550 -3900) $PN 2
J 0
(-1530 -3890);
DISPLAY 0.617021 (-1530 -3890);
PAINT MONO (-1530 -3890);
FORCEPROP 0 LAST GROUP AST2500
J 0
(-1600 -4125);
DISPLAY 0.638298 (-1600 -4125);
PAINT BROWN (-1600 -4125);
DISPLAY BOTH (-1600 -4125);
FORCEPROP 1 LAST PACK_TYPE 0402V
J 0
(-1600 -4075);
DISPLAY 0.617021 (-1600 -4075);
PAINT SKYBLUE (-1600 -4075);
FORCEPROP 1 LAST MATERIAL X7R
J 0
(-1600 -3975);
DISPLAY 0.617021 (-1600 -3975);
PAINT SKYBLUE (-1600 -3975);
FORCEPROP 1 LAST LOCATION C25W21
J 0
(-1800 -3975);
DISPLAY 0.617021 (-1800 -3975);
PAINT AQUA (-1800 -3975);
FORCEPROP 1 LAST PART_NUMBER A36096-030
J 0
(-1600 -4025);
DISPLAY 0.617021 (-1600 -4025);
PAINT BLUE (-1600 -4025);
FORCEPROP 1 LAST PATH I159
R 1
J 0
(-1800 -3850);
DISPLAY 0.978723 (-1800 -3850);
PAINT WHITE (-1800 -3850);
DISPLAY INVISIBLE (-1800 -3850);
FORCEPROP 2 LAST SEC 1
R 1
J 0
(-1850 -3850);
DISPLAY 0.936170 (-1850 -3850);
PAINT MONO (-1850 -3850);
DISPLAY INVISIBLE (-1850 -3850);
FORCEPROP 2 LAST SEC_TYPE 0402V
R 1
J 0
(-1850 -3850);
PAINT MONO (-1850 -3850);
DISPLAY INVISIBLE (-1850 -3850);
FORCEPROP 2 LAST CDS_SEC 1
R 1
J 0
(-1800 -3850);
PAINT ORANGE (-1800 -3850);
DISPLAY INVISIBLE (-1800 -3850);
FORCEPROP 2 LAST CDS_LIB dev_discrete
R 1
J 0
(-1650 -3900);
PAINT ORANGE (-1650 -3900);
DISPLAY INVISIBLE (-1650 -3900);
FORCEPROP 2 LAST BOM_COST PROC_SIDEBAND
R 1
J 0
(-1650 -3900);
PAINT MONO (-1650 -3900);
DISPLAY INVISIBLE (-1650 -3900);
FORCEPROP 2 LAST ROOM PROC_SIDEBAND
R 1
J 0
(-1400 -3850);
DISPLAY 0.978723 (-1400 -3850);
PAINT ORANGE (-1400 -3850);
DISPLAY INVISIBLE (-1400 -3850);
FORCEPROP 2 LAST CDS_LOCATION C25W21
R 1
J 0
(-1750 -3850);
DISPLAY 0.617021 (-1750 -3850);
PAINT AQUA (-1750 -3850);
DISPLAY INVISIBLE (-1750 -3850);
FORCEADD P3V3_STBY..1
(-7500 -200);
FORCEPROP 3 LASTPIN (-7500 -250) SIG_NAME P3V3_STBY\g
J 0
(-7490 -240);
DISPLAY 0.659574 (-7490 -240);
PAINT MONO (-7490 -240);
DISPLAY INVISIBLE (-7490 -240);
FORCEPROP 1 LAST HDL_POWER P3V3_STBY
J 0
(-7800 -325);
DISPLAY 0.872340 (-7800 -325);
PAINT ORANGE (-7800 -325);
DISPLAY INVISIBLE (-7800 -325);
FORCEPROP 1 LAST BODY_TYPE PLUMBING
J 0
(-7545 -243);
DISPLAY 0.340426 (-7545 -243);
PAINT GREEN (-7545 -243);
DISPLAY INVISIBLE (-7545 -243);
FORCEPROP 1 LAST VOLTAGE 3.3V
J 0
(-7545 -243);
DISPLAY 0.340426 (-7545 -243);
PAINT SKYBLUE (-7545 -243);
DISPLAY INVISIBLE (-7545 -243);
FORCEPROP 2 LAST CDS_LIB mstr_symbols
J 0
(-7500 -200);
PAINT ORANGE (-7500 -200);
DISPLAY INVISIBLE (-7500 -200);
FORCEPROP 1 LAST SIZE 1B
J 0
(-7455 -178);
DISPLAY 0.340426 (-7455 -178);
PAINT GREEN (-7455 -178);
DISPLAY INVISIBLE (-7455 -178);
FORCEPROP 1 LAST PATH I16
J 0
(-7455 -198);
DISPLAY 0.340426 (-7455 -198);
PAINT GREEN (-7455 -198);
DISPLAY INVISIBLE (-7455 -198);
FORCEADD RES..1
(-5950 -3450);
FORCEPROP 1 LAST PART_NUMBER G21497-005
J 0
(-6125 -3400);
DISPLAY 0.617021 (-6125 -3400);
PAINT BLUE (-6125 -3400);
FORCEPROP 1 LAST LOCATION R25W141
J 0
(-6250 -3500);
DISPLAY 0.617021 (-6250 -3500);
PAINT AQUA (-6250 -3500);
FORCEPROP 1 LAST PACK_TYPE 0402
J 0
(-5725 -3400);
DISPLAY 0.617021 (-5725 -3400);
PAINT SKYBLUE (-5725 -3400);
FORCEPROP 1 LASTPIN (-6050 -3450) $PN 1
J 0
(-6038 -3438);
DISPLAY 0.617021 (-6038 -3438);
PAINT WHITE (-6038 -3438);
FORCEPROP 1 LAST VALUE 0.0
J 2
(-5850 -3400);
DISPLAY 0.617021 (-5850 -3400);
PAINT SKYBLUE (-5850 -3400);
FORCEPROP 1 LAST TOLERANCE 5%
J 0
(-5825 -3400);
DISPLAY 0.617021 (-5825 -3400);
PAINT SKYBLUE (-5825 -3400);
FORCEPROP 0 LAST GROUP AST2500
J 0
(-6050 -3500);
DISPLAY 0.638298 (-6050 -3500);
PAINT BROWN (-6050 -3500);
DISPLAY BOTH (-6050 -3500);
FORCEPROP 1 LASTPIN (-5850 -3450) $PN 2
J 0
(-5888 -3438);
DISPLAY 0.617021 (-5888 -3438);
PAINT WHITE (-5888 -3438);
FORCEPROP 1 LAST PATH I160
J 0
(-6000 -3300);
DISPLAY 0.978723 (-6000 -3300);
PAINT WHITE (-6000 -3300);
DISPLAY INVISIBLE (-6000 -3300);
FORCEPROP 1 LAST MATERIAL CHIP
J 0
(-5800 -3550);
DISPLAY 0.510638 (-5800 -3550);
PAINT SKYBLUE (-5800 -3550);
DISPLAY INVISIBLE (-5800 -3550);
FORCEPROP 1 LAST WATTAGE 1/16W
J 2
(-5425 -3475);
DISPLAY 0.510638 (-5425 -3475);
PAINT SKYBLUE (-5425 -3475);
DISPLAY INVISIBLE (-5425 -3475);
FORCEPROP 2 LAST BOM_COST PROC_SIDEBAND
J 0
(-5950 -3450);
PAINT MONO (-5950 -3450);
DISPLAY INVISIBLE (-5950 -3450);
FORCEPROP 2 LAST CDS_LIB mstr_discrete
J 0
(-5950 -3450);
DISPLAY 1.340426 (-5950 -3450);
PAINT ORANGE (-5950 -3450);
DISPLAY INVISIBLE (-5950 -3450);
FORCEPROP 2 LAST SEC_TYPE 0402
J 0
(-6000 -3225);
DISPLAY 1.021277 (-6000 -3225);
PAINT ORANGE (-6000 -3225);
DISPLAY INVISIBLE (-6000 -3225);
FORCEPROP 2 LAST SEC 1
J 0
(-6000 -3225);
DISPLAY 0.680851 (-6000 -3225);
PAINT MONO (-6000 -3225);
DISPLAY INVISIBLE (-6000 -3225);
FORCEPROP 2 LAST ROOM CPU0
J 0
(-6000 -3300);
PAINT PEACH (-6000 -3300);
DISPLAY INVISIBLE (-6000 -3300);
FORCEPROP 2 LAST CDS_LOCATION R25W141
J 0
(-6425 -3450);
DISPLAY 0.617021 (-6425 -3450);
PAINT AQUA (-6425 -3450);
DISPLAY INVISIBLE (-6425 -3450);
FORCEADD OFFPAGE..3
R 2
(-7750 -1850);
FORCEPROP 2 LAST $XR0 248 
J 0
(-8030 -1850);
DISPLAY 0.638298 (-8030 -1850);
PAINT MONO (-8030 -1850);
FORCEPROP 2 LAST CDS_LIB mstr_standard
J 0
(-7750 -1850);
PAINT MONO (-7750 -1850);
DISPLAY INVISIBLE (-7750 -1850);
FORCEPROP 2 LAST PATH I161
J 0
(-7700 -1775);
DISPLAY 1.021277 (-7700 -1775);
PAINT ORANGE (-7700 -1775);
DISPLAY INVISIBLE (-7700 -1775);
FORCEPROP 1 LAST COMMENT_BODY TRUE
J 2
(-7700 -1950);
DISPLAY 0.872340 (-7700 -1950);
PAINT GREEN (-7700 -1950);
DISPLAY INVISIBLE (-7700 -1950);
FORCEPROP 1 LAST OFFPAGE TRUE
J 2
(-8075 -1975);
DISPLAY 0.872340 (-8075 -1975);
PAINT GREEN (-8075 -1975);
DISPLAY INVISIBLE (-8075 -1975);
FORCEADD OFFPAGE..1
(-7750 -1900);
FORCEPROP 2 LAST $XR0 248 
J 0
(-8032 -1900);
DISPLAY 0.638298 (-8032 -1900);
PAINT MONO (-8032 -1900);
FORCEPROP 2 LAST CDS_LIB mstr_standard
J 0
(-7750 -1900);
PAINT MONO (-7750 -1900);
DISPLAY INVISIBLE (-7750 -1900);
FORCEPROP 2 LAST PATH I162
J 0
(-7700 -1825);
DISPLAY 1.021277 (-7700 -1825);
PAINT ORANGE (-7700 -1825);
DISPLAY INVISIBLE (-7700 -1825);
FORCEPROP 1 LAST COMMENT_BODY TRUE
J 0
(-7625 -2000);
DISPLAY 0.872340 (-7625 -2000);
PAINT GREEN (-7625 -2000);
DISPLAY INVISIBLE (-7625 -2000);
FORCEPROP 1 LAST OFFPAGE TRUE
J 0
(-7425 -2025);
DISPLAY 0.872340 (-7425 -2025);
PAINT GREEN (-7425 -2025);
DISPLAY INVISIBLE (-7425 -2025);
FORCEPROP 2 LAST ROOM BMC
J 0
(-8000 -1825);
DISPLAY 1.361702 (-8000 -1825);
PAINT ORANGE (-8000 -1825);
DISPLAY INVISIBLE (-8000 -1825);
FORCEPROP 2 LAST BOM_COST SM_CONTROLLER
J 0
(-7300 -1850);
PAINT MONO (-7300 -1850);
DISPLAY INVISIBLE (-7300 -1850);
FORCEADD RES..1
(-6450 -1850);
FORCEPROP 1 LAST PART_NUMBER G21796-173
J 0
(-6125 -1800);
DISPLAY 0.617021 (-6125 -1800);
PAINT BLUE (-6125 -1800);
FORCEPROP 1 LAST VALUE 20.0
J 2
(-6675 -1800);
DISPLAY 0.617021 (-6675 -1800);
PAINT SKYBLUE (-6675 -1800);
FORCEPROP 1 LAST TOLERANCE 1%
J 0
(-6625 -1800);
DISPLAY 0.617021 (-6625 -1800);
PAINT SKYBLUE (-6625 -1800);
FORCEPROP 1 LAST LOCATION R25W121
J 0
(-6775 -1850);
DISPLAY 0.617021 (-6775 -1850);
PAINT AQUA (-6775 -1850);
FORCEPROP 1 LASTPIN (-6550 -1850) $PN 1
J 0
(-6538 -1838);
DISPLAY 0.787234 (-6538 -1838);
PAINT ORANGE (-6538 -1838);
FORCEPROP 1 LAST WATTAGE 1/16W
J 2
(-6425 -1800);
DISPLAY 0.617021 (-6425 -1800);
PAINT SKYBLUE (-6425 -1800);
FORCEPROP 1 LASTPIN (-6350 -1850) $PN 2
J 0
(-6388 -1838);
DISPLAY 0.787234 (-6388 -1838);
PAINT ORANGE (-6388 -1838);
FORCEPROP 1 LAST MATERIAL CHIP
J 0
(-6300 -1850);
DISPLAY 0.617021 (-6300 -1850);
PAINT SKYBLUE (-6300 -1850);
FORCEPROP 1 LAST PACK_TYPE 0402
J 0
(-6175 -1850);
DISPLAY 0.617021 (-6175 -1850);
PAINT SKYBLUE (-6175 -1850);
FORCEPROP 2 LAST SEC 1
J 0
(-6500 -1650);
DISPLAY 0.680851 (-6500 -1650);
PAINT MONO (-6500 -1650);
DISPLAY INVISIBLE (-6500 -1650);
FORCEPROP 2 LAST SEC_TYPE 0402
J 0
(-6500 -1650);
DISPLAY 1.021277 (-6500 -1650);
PAINT ORANGE (-6500 -1650);
DISPLAY INVISIBLE (-6500 -1650);
FORCEPROP 2 LAST CDS_LIB mstr_discrete
J 0
(-6450 -1850);
PAINT MONO (-6450 -1850);
DISPLAY INVISIBLE (-6450 -1850);
FORCEPROP 1 LAST PATH I163
J 0
(-6500 -1700);
DISPLAY 0.978723 (-6500 -1700);
PAINT WHITE (-6500 -1700);
DISPLAY INVISIBLE (-6500 -1700);
FORCEPROP 0 LAST ROOM SMB_PE_HP_CPU1
J 0
(-6500 -1650);
DISPLAY 1.021277 (-6500 -1650);
PAINT ORANGE (-6500 -1650);
DISPLAY INVISIBLE (-6500 -1650);
FORCEADD RES..1
(-6450 -1900);
FORCEPROP 1 LAST MATERIAL CHIP
J 0
(-6300 -1900);
DISPLAY 0.617021 (-6300 -1900);
PAINT SKYBLUE (-6300 -1900);
FORCEPROP 1 LASTPIN (-6350 -1900) $PN 2
J 0
(-6388 -1888);
DISPLAY 0.787234 (-6388 -1888);
PAINT ORANGE (-6388 -1888);
FORCEPROP 1 LASTPIN (-6550 -1900) $PN 1
J 0
(-6538 -1888);
DISPLAY 0.787234 (-6538 -1888);
PAINT ORANGE (-6538 -1888);
FORCEPROP 1 LAST PACK_TYPE 0402
J 0
(-6175 -1900);
DISPLAY 0.617021 (-6175 -1900);
PAINT SKYBLUE (-6175 -1900);
FORCEPROP 1 LAST LOCATION R25W122
J 0
(-6775 -1900);
DISPLAY 0.617021 (-6775 -1900);
PAINT AQUA (-6775 -1900);
FORCEPROP 1 LAST VALUE 20.0
J 2
(-6675 -1950);
DISPLAY 0.617021 (-6675 -1950);
PAINT SKYBLUE (-6675 -1950);
FORCEPROP 1 LAST TOLERANCE 1%
J 0
(-6625 -1950);
DISPLAY 0.617021 (-6625 -1950);
PAINT SKYBLUE (-6625 -1950);
FORCEPROP 1 LAST WATTAGE 1/16W
J 2
(-6425 -1950);
DISPLAY 0.617021 (-6425 -1950);
PAINT SKYBLUE (-6425 -1950);
FORCEPROP 1 LAST PART_NUMBER G21796-173
J 0
(-6375 -1950);
DISPLAY 0.617021 (-6375 -1950);
PAINT BLUE (-6375 -1950);
FORCEPROP 1 LAST PATH I164
J 0
(-6500 -1750);
DISPLAY 0.978723 (-6500 -1750);
PAINT WHITE (-6500 -1750);
DISPLAY INVISIBLE (-6500 -1750);
FORCEPROP 0 LAST ROOM SMB_PE_HP_CPU1
J 0
(-6500 -1700);
DISPLAY 1.021277 (-6500 -1700);
PAINT ORANGE (-6500 -1700);
DISPLAY INVISIBLE (-6500 -1700);
FORCEPROP 2 LAST CDS_LIB mstr_discrete
J 0
(-6450 -1900);
PAINT MONO (-6450 -1900);
DISPLAY INVISIBLE (-6450 -1900);
FORCEPROP 2 LAST SEC_TYPE 0402
J 0
(-6500 -1700);
DISPLAY 1.021277 (-6500 -1700);
PAINT ORANGE (-6500 -1700);
DISPLAY INVISIBLE (-6500 -1700);
FORCEPROP 2 LAST SEC 1
J 0
(-6500 -1700);
DISPLAY 0.680851 (-6500 -1700);
PAINT MONO (-6500 -1700);
DISPLAY INVISIBLE (-6500 -1700);
FORCEADD OFFPAGE..4
R 2
(-6150 -1500);
FORCEPROP 2 LAST PATH I165
J 0
(-6400 -1450);
DISPLAY 1.021277 (-6400 -1450);
PAINT ORANGE (-6400 -1450);
DISPLAY INVISIBLE (-6400 -1450);
FORCEPROP 2 LAST CDS_LIB mstr_standard
J 2
(-6150 -1500);
PAINT MONO (-6150 -1500);
DISPLAY INVISIBLE (-6150 -1500);
FORCEPROP 1 LAST OFFPAGE TRUE
J 2
(-6475 -1625);
DISPLAY 0.872340 (-6475 -1625);
PAINT GREEN (-6475 -1625);
DISPLAY INVISIBLE (-6475 -1625);
FORCEPROP 1 LAST COMMENT_BODY TRUE
J 2
(-6125 -1600);
DISPLAY 0.872340 (-6125 -1600);
PAINT GREEN (-6125 -1600);
DISPLAY INVISIBLE (-6125 -1600);
FORCEPROP 2 LAST $XR1 120 
J 0
(-6576 -1500);
DISPLAY 0.638298 (-6576 -1500);
PAINT MONO (-6576 -1500);
DISPLAY INVISIBLE (-6576 -1500);
FORCEPROP 2 LAST $XR0 89 
J 0
(-6576 -1500);
DISPLAY 0.638298 (-6576 -1500);
PAINT MONO (-6576 -1500);
DISPLAY INVISIBLE (-6576 -1500);
FORCEADD OFFPAGE..4
R 2
(-6150 -1600);
FORCEPROP 2 LAST $XR2 190 
J 0
(-6672 -1600);
DISPLAY 0.638298 (-6672 -1600);
PAINT MONO (-6672 -1600);
FORCEPROP 2 LAST $XR1 120 
J 0
(-6552 -1600);
DISPLAY 0.638298 (-6552 -1600);
PAINT MONO (-6552 -1600);
FORCEPROP 2 LAST $XR0 168 
J 0
(-6432 -1600);
DISPLAY 0.638298 (-6432 -1600);
PAINT MONO (-6432 -1600);
FORCEPROP 2 LAST PATH I166
J 0
(-6425 -1550);
DISPLAY 1.021277 (-6425 -1550);
PAINT ORANGE (-6425 -1550);
DISPLAY INVISIBLE (-6425 -1550);
FORCEPROP 2 LAST CDS_LIB mstr_standard
J 2
(-6150 -1600);
PAINT MONO (-6150 -1600);
DISPLAY INVISIBLE (-6150 -1600);
FORCEPROP 1 LAST OFFPAGE TRUE
J 2
(-6475 -1725);
DISPLAY 0.872340 (-6475 -1725);
PAINT GREEN (-6475 -1725);
DISPLAY INVISIBLE (-6475 -1725);
FORCEPROP 1 LAST COMMENT_BODY TRUE
J 2
(-6125 -1700);
DISPLAY 0.872340 (-6125 -1700);
PAINT GREEN (-6125 -1700);
DISPLAY INVISIBLE (-6125 -1700);
FORCEADD OFFPAGE..2
R 2
(-6150 -1750);
FORCEPROP 2 LAST $XR0 120 
J 0
(-6405 -1750);
DISPLAY 0.638298 (-6405 -1750);
PAINT MONO (-6405 -1750);
FORCEPROP 2 LAST PATH I167
J 0
(-6400 -1700);
DISPLAY 1.021277 (-6400 -1700);
PAINT ORANGE (-6400 -1700);
DISPLAY INVISIBLE (-6400 -1700);
FORCEPROP 1 LAST COMMENT_BODY TRUE
J 2
(-6105 -1845);
DISPLAY 0.872340 (-6105 -1845);
PAINT GREEN (-6105 -1845);
DISPLAY INVISIBLE (-6105 -1845);
FORCEPROP 1 LAST OFFPAGE TRUE
J 2
(-6475 -1875);
DISPLAY 0.872340 (-6475 -1875);
PAINT GREEN (-6475 -1875);
DISPLAY INVISIBLE (-6475 -1875);
FORCEPROP 2 LAST CDS_LIB mstr_standard
J 2
(-6150 -1750);
PAINT MONO (-6150 -1750);
DISPLAY INVISIBLE (-6150 -1750);
FORCEADD OFFPAGE..1
(-6150 -1450);
FORCEPROP 2 LAST PATH I168
J 0
(-6425 -1400);
DISPLAY 1.021277 (-6425 -1400);
PAINT ORANGE (-6425 -1400);
DISPLAY INVISIBLE (-6425 -1400);
FORCEPROP 1 LAST COMMENT_BODY TRUE
J 0
(-6025 -1550);
DISPLAY 0.872340 (-6025 -1550);
PAINT GREEN (-6025 -1550);
DISPLAY INVISIBLE (-6025 -1550);
FORCEPROP 1 LAST OFFPAGE TRUE
J 0
(-5825 -1575);
DISPLAY 0.872340 (-5825 -1575);
PAINT GREEN (-5825 -1575);
DISPLAY INVISIBLE (-5825 -1575);
FORCEPROP 2 LAST CDS_LIB mstr_standard
J 0
(-6150 -1450);
PAINT MONO (-6150 -1450);
DISPLAY INVISIBLE (-6150 -1450);
FORCEPROP 2 LAST ROOM BMC
J 0
(-6400 -1375);
DISPLAY 1.361702 (-6400 -1375);
PAINT ORANGE (-6400 -1375);
DISPLAY INVISIBLE (-6400 -1375);
FORCEPROP 2 LAST BOM_COST SM_CONTROLLER
J 0
(-5700 -1400);
PAINT MONO (-5700 -1400);
DISPLAY INVISIBLE (-5700 -1400);
FORCEPROP 2 LAST $XR1 119 
J 0
(-6576 -1450);
DISPLAY 0.638298 (-6576 -1450);
PAINT MONO (-6576 -1450);
DISPLAY INVISIBLE (-6576 -1450);
FORCEPROP 2 LAST $XR0 164 
J 0
(-6576 -1450);
DISPLAY 0.638298 (-6576 -1450);
PAINT MONO (-6576 -1450);
DISPLAY INVISIBLE (-6576 -1450);
FORCEADD OFFPAGE..1
(-6150 -1550);
FORCEPROP 2 LAST $XR1 119 
J 0
(-6552 -1550);
DISPLAY 0.638298 (-6552 -1550);
PAINT MONO (-6552 -1550);
FORCEPROP 2 LAST $XR0 164 
J 0
(-6432 -1550);
DISPLAY 0.638298 (-6432 -1550);
PAINT MONO (-6432 -1550);
FORCEPROP 2 LAST PATH I169
J 0
(-6425 -1500);
DISPLAY 1.021277 (-6425 -1500);
PAINT ORANGE (-6425 -1500);
DISPLAY INVISIBLE (-6425 -1500);
FORCEPROP 2 LAST BOM_COST SM_CONTROLLER
J 0
(-5700 -1500);
PAINT MONO (-5700 -1500);
DISPLAY INVISIBLE (-5700 -1500);
FORCEPROP 2 LAST ROOM BMC
J 0
(-6400 -1475);
DISPLAY 1.361702 (-6400 -1475);
PAINT ORANGE (-6400 -1475);
DISPLAY INVISIBLE (-6400 -1475);
FORCEPROP 1 LAST OFFPAGE TRUE
J 0
(-5825 -1675);
DISPLAY 0.872340 (-5825 -1675);
PAINT GREEN (-5825 -1675);
DISPLAY INVISIBLE (-5825 -1675);
FORCEPROP 1 LAST COMMENT_BODY TRUE
J 0
(-6025 -1650);
DISPLAY 0.872340 (-6025 -1650);
PAINT GREEN (-6025 -1650);
DISPLAY INVISIBLE (-6025 -1650);
FORCEPROP 2 LAST CDS_LIB mstr_standard
J 0
(-6150 -1550);
PAINT MONO (-6150 -1550);
DISPLAY INVISIBLE (-6150 -1550);
FORCEADD GND..1
(-7500 -675);
FORCEPROP 3 LASTPIN (-7500 -625) SIG_NAME GND\g
J 0
(-7490 -615);
DISPLAY 0.659574 (-7490 -615);
PAINT MONO (-7490 -615);
DISPLAY INVISIBLE (-7490 -615);
FORCEPROP 1 LAST HDL_POWER GND
J 0
(-7500 -525);
DISPLAY 0.872340 (-7500 -525);
PAINT GREEN (-7500 -525);
DISPLAY INVISIBLE (-7500 -525);
FORCEPROP 1 LAST BODY_TYPE PLUMBING
J 0
(-7545 -718);
DISPLAY 0.340426 (-7545 -718);
PAINT GREEN (-7545 -718);
DISPLAY INVISIBLE (-7545 -718);
FORCEPROP 2 LAST CDS_LIB mstr_symbols
J 0
(-7500 -675);
PAINT ORANGE (-7500 -675);
DISPLAY INVISIBLE (-7500 -675);
FORCEPROP 1 LAST VOLTAGE 0.0V
J 0
(-7545 -718);
DISPLAY 0.340426 (-7545 -718);
PAINT SKYBLUE (-7545 -718);
DISPLAY INVISIBLE (-7545 -718);
FORCEPROP 1 LAST SIZE 1B
J 0
(-7425 -725);
DISPLAY 0.872340 (-7425 -725);
PAINT AQUA (-7425 -725);
DISPLAY INVISIBLE (-7425 -725);
FORCEPROP 1 LAST PATH I17
J 0
(-7425 -675);
DISPLAY 0.872340 (-7425 -675);
PAINT AQUA (-7425 -675);
DISPLAY INVISIBLE (-7425 -675);
FORCEADD OFFPAGE..1
(-6150 -1700);
FORCEPROP 2 LAST $XR1 119 
J 0
(-6552 -1700);
DISPLAY 0.638298 (-6552 -1700);
PAINT MONO (-6552 -1700);
FORCEPROP 2 LAST $XR0 164 
J 0
(-6432 -1700);
DISPLAY 0.638298 (-6432 -1700);
PAINT MONO (-6432 -1700);
FORCEPROP 2 LAST PATH I170
J 0
(-6500 -1650);
DISPLAY 1.021277 (-6500 -1650);
PAINT ORANGE (-6500 -1650);
DISPLAY INVISIBLE (-6500 -1650);
FORCEPROP 2 LAST BOM_COST SM_CONTROLLER
J 0
(-5700 -1650);
PAINT MONO (-5700 -1650);
DISPLAY INVISIBLE (-5700 -1650);
FORCEPROP 2 LAST ROOM BMC
J 0
(-6400 -1625);
DISPLAY 1.361702 (-6400 -1625);
PAINT ORANGE (-6400 -1625);
DISPLAY INVISIBLE (-6400 -1625);
FORCEPROP 2 LAST CDS_LIB mstr_standard
J 0
(-6150 -1700);
PAINT MONO (-6150 -1700);
DISPLAY INVISIBLE (-6150 -1700);
FORCEPROP 1 LAST OFFPAGE TRUE
J 0
(-5825 -1825);
DISPLAY 0.872340 (-5825 -1825);
PAINT GREEN (-5825 -1825);
DISPLAY INVISIBLE (-5825 -1825);
FORCEPROP 1 LAST COMMENT_BODY TRUE
J 0
(-6025 -1800);
DISPLAY 0.872340 (-6025 -1800);
PAINT GREEN (-6025 -1800);
DISPLAY INVISIBLE (-6025 -1800);
FORCEADD OFFPAGE..4
(-800 -2900);
FORCEPROP 2 LAST $XR2 190 
J 0
(-494 -2936);
DISPLAY 0.638298 (-494 -2936);
PAINT MONO (-494 -2936);
FORCEPROP 2 LAST $XR1 119 
J 0
(-494 -2900);
DISPLAY 0.638298 (-494 -2900);
PAINT MONO (-494 -2900);
FORCEPROP 2 LAST $XR0 175 
J 0
(-614 -2900);
DISPLAY 0.638298 (-614 -2900);
PAINT MONO (-614 -2900);
FORCEPROP 2 LAST PATH I172
J 0
(-350 -2850);
DISPLAY 1.021277 (-350 -2850);
PAINT ORANGE (-350 -2850);
DISPLAY INVISIBLE (-350 -2850);
FORCEPROP 1 LAST COMMENT_BODY TRUE
J 0
(-825 -3000);
DISPLAY 0.872340 (-825 -3000);
PAINT GREEN (-825 -3000);
DISPLAY INVISIBLE (-825 -3000);
FORCEPROP 1 LAST OFFPAGE TRUE
J 0
(-475 -3025);
DISPLAY 0.872340 (-475 -3025);
PAINT GREEN (-475 -3025);
DISPLAY INVISIBLE (-475 -3025);
FORCEPROP 2 LAST CDS_LIB mstr_standard
J 0
(-800 -2900);
PAINT MONO (-800 -2900);
DISPLAY INVISIBLE (-800 -2900);
FORCEADD RES..1
(-1500 -2900);
FORCEPROP 1 LAST WATTAGE 1/16W
J 0
(-1025 -2950);
DISPLAY 0.638298 (-1025 -2950);
PAINT SKYBLUE (-1025 -2950);
FORCEPROP 1 LAST MATERIAL CHIP
J 0
(-1300 -2950);
DISPLAY 0.617021 (-1300 -2950);
PAINT SKYBLUE (-1300 -2950);
FORCEPROP 1 LASTPIN (-1600 -2900) $PN 1
J 0
(-1588 -2888);
DISPLAY 0.617021 (-1588 -2888);
PAINT ORANGE (-1588 -2888);
FORCEPROP 1 LAST VALUE 0.0
J 0
(-1175 -2850);
DISPLAY 0.617021 (-1175 -2850);
PAINT SKYBLUE (-1175 -2850);
FORCEPROP 1 LAST TOLERANCE 5%
J 0
(-1075 -2850);
DISPLAY 0.617021 (-1075 -2850);
PAINT SKYBLUE (-1075 -2850);
FORCEPROP 1 LASTPIN (-1400 -2900) $PN 2
J 0
(-1438 -2888);
DISPLAY 0.617021 (-1438 -2888);
PAINT ORANGE (-1438 -2888);
FORCEPROP 1 LAST LOCATION R25W144
J 0
(-1400 -2850);
DISPLAY 0.617021 (-1400 -2850);
PAINT AQUA (-1400 -2850);
FORCEPROP 1 LAST PART_NUMBER G21497-005
J 0
(-1550 -2950);
DISPLAY 0.617021 (-1550 -2950);
PAINT BLUE (-1550 -2950);
FORCEPROP 0 LAST SEC_TYPE 0402
J 0
(-1175 -2950);
DISPLAY 0.638298 (-1175 -2950);
PAINT SKYBLUE (-1175 -2950);
FORCEPROP 2 LAST CDS_LOCATION R25W144
J 0
(-1900 -2900);
DISPLAY 0.617021 (-1900 -2900);
PAINT AQUA (-1900 -2900);
DISPLAY INVISIBLE (-1900 -2900);
FORCEPROP 2 LAST CDS_LIB mstr_discrete
J 0
(-1500 -2900);
PAINT ORANGE (-1500 -2900);
DISPLAY INVISIBLE (-1500 -2900);
FORCEPROP 2 LAST SEC 1
J 0
(-1550 -2700);
DISPLAY 0.680851 (-1550 -2700);
PAINT MONO (-1550 -2700);
DISPLAY INVISIBLE (-1550 -2700);
FORCEPROP 0 LAST ROOM BMC
J 0
(-1550 -2700);
DISPLAY 1.021277 (-1550 -2700);
PAINT ORANGE (-1550 -2700);
DISPLAY INVISIBLE (-1550 -2700);
FORCEPROP 0 LAST BOM_COST SM_CONTROLLER
J 0
(-1550 -2600);
DISPLAY 1.021277 (-1550 -2600);
PAINT ORANGE (-1550 -2600);
DISPLAY INVISIBLE (-1550 -2600);
FORCEPROP 1 LAST PACK_TYPE 0402
J 0
(-1250 -3050);
DISPLAY 0.978723 (-1250 -3050);
PAINT SKYBLUE (-1250 -3050);
DISPLAY INVISIBLE (-1250 -3050);
FORCEPROP 0 LAST CDS_SEC 1
J 0
(-1375 -2850);
PAINT MONO (-1375 -2850);
DISPLAY INVISIBLE (-1375 -2850);
FORCEPROP 1 LAST PATH I173
J 0
(-1550 -2750);
DISPLAY 0.978723 (-1550 -2750);
PAINT WHITE (-1550 -2750);
DISPLAY INVISIBLE (-1550 -2750);
FORCEADD OFFPAGE..4
(-800 -3000);
FORCEPROP 2 LAST $XR1 119 
J 0
(-494 -3000);
DISPLAY 0.638298 (-494 -3000);
PAINT MONO (-494 -3000);
FORCEPROP 2 LAST $XR0 175 
J 0
(-614 -3000);
DISPLAY 0.638298 (-614 -3000);
PAINT MONO (-614 -3000);
FORCEPROP 2 LAST PATH I174
J 0
(-475 -2950);
DISPLAY 1.021277 (-475 -2950);
PAINT ORANGE (-475 -2950);
DISPLAY INVISIBLE (-475 -2950);
FORCEPROP 1 LAST COMMENT_BODY TRUE
J 0
(-825 -3100);
DISPLAY 0.872340 (-825 -3100);
PAINT GREEN (-825 -3100);
DISPLAY INVISIBLE (-825 -3100);
FORCEPROP 1 LAST OFFPAGE TRUE
J 0
(-475 -3125);
DISPLAY 0.872340 (-475 -3125);
PAINT GREEN (-475 -3125);
DISPLAY INVISIBLE (-475 -3125);
FORCEPROP 2 LAST CDS_LIB mstr_standard
J 0
(-800 -3000);
PAINT MONO (-800 -3000);
DISPLAY INVISIBLE (-800 -3000);
FORCEADD RES..1
(-1500 -3000);
FORCEPROP 1 LAST WATTAGE 1/16W
J 0
(-1025 -3050);
DISPLAY 0.638298 (-1025 -3050);
PAINT SKYBLUE (-1025 -3050);
FORCEPROP 1 LAST VALUE 0.0
J 0
(-1725 -3050);
DISPLAY 0.617021 (-1725 -3050);
PAINT SKYBLUE (-1725 -3050);
FORCEPROP 1 LAST LOCATION R25W145
J 0
(-1950 -3050);
DISPLAY 0.617021 (-1950 -3050);
PAINT AQUA (-1950 -3050);
FORCEPROP 1 LASTPIN (-1600 -3000) $PN 1
J 0
(-1588 -2988);
DISPLAY 0.617021 (-1588 -2988);
PAINT ORANGE (-1588 -2988);
FORCEPROP 1 LAST TOLERANCE 5%
J 0
(-1625 -3050);
DISPLAY 0.617021 (-1625 -3050);
PAINT SKYBLUE (-1625 -3050);
FORCEPROP 1 LAST MATERIAL CHIP
J 0
(-1275 -3050);
DISPLAY 0.617021 (-1275 -3050);
PAINT SKYBLUE (-1275 -3050);
FORCEPROP 1 LASTPIN (-1400 -3000) $PN 2
J 0
(-1438 -2988);
DISPLAY 0.617021 (-1438 -2988);
PAINT ORANGE (-1438 -2988);
FORCEPROP 1 LAST PART_NUMBER G21497-005
J 0
(-1525 -3050);
DISPLAY 0.617021 (-1525 -3050);
PAINT BLUE (-1525 -3050);
FORCEPROP 0 LAST SEC_TYPE 0402
J 0
(-1150 -3050);
DISPLAY 0.638298 (-1150 -3050);
PAINT SKYBLUE (-1150 -3050);
FORCEPROP 2 LAST CDS_LOCATION R25W145
J 0
(-1900 -3000);
DISPLAY 0.617021 (-1900 -3000);
PAINT AQUA (-1900 -3000);
DISPLAY INVISIBLE (-1900 -3000);
FORCEPROP 1 LAST PATH I175
J 0
(-1550 -2850);
DISPLAY 0.978723 (-1550 -2850);
PAINT WHITE (-1550 -2850);
DISPLAY INVISIBLE (-1550 -2850);
FORCEPROP 0 LAST CDS_SEC 1
J 0
(-1375 -2950);
PAINT MONO (-1375 -2950);
DISPLAY INVISIBLE (-1375 -2950);
FORCEPROP 1 LAST PACK_TYPE 0402
J 0
(-1250 -3150);
DISPLAY 0.978723 (-1250 -3150);
PAINT SKYBLUE (-1250 -3150);
DISPLAY INVISIBLE (-1250 -3150);
FORCEPROP 0 LAST BOM_COST SM_CONTROLLER
J 0
(-1550 -2700);
DISPLAY 1.021277 (-1550 -2700);
PAINT ORANGE (-1550 -2700);
DISPLAY INVISIBLE (-1550 -2700);
FORCEPROP 0 LAST ROOM BMC
J 0
(-1550 -2800);
DISPLAY 1.021277 (-1550 -2800);
PAINT ORANGE (-1550 -2800);
DISPLAY INVISIBLE (-1550 -2800);
FORCEPROP 2 LAST SEC 1
J 0
(-1550 -2800);
DISPLAY 0.680851 (-1550 -2800);
PAINT MONO (-1550 -2800);
DISPLAY INVISIBLE (-1550 -2800);
FORCEPROP 2 LAST CDS_LIB mstr_discrete
J 0
(-1500 -3000);
PAINT ORANGE (-1500 -3000);
DISPLAY INVISIBLE (-1500 -3000);
FORCEADD RES..1
(-1500 -1850);
FORCEPROP 1 LAST LOCATION R2W5
J 0
(-1725 -1750);
DISPLAY 0.617021 (-1725 -1750);
PAINT AQUA (-1725 -1750);
FORCEPROP 1 LASTPIN (-1600 -1850) $PN 1
J 0
(-1588 -1838);
DISPLAY 0.617021 (-1588 -1838);
PAINT WHITE (-1588 -1838);
FORCEPROP 1 LASTPIN (-1400 -1850) $PN 2
J 0
(-1438 -1838);
DISPLAY 0.617021 (-1438 -1838);
PAINT WHITE (-1438 -1838);
FORCEPROP 1 LAST VALUE 0.0
J 0
(-1750 -1800);
DISPLAY 0.617021 (-1750 -1800);
PAINT SKYBLUE (-1750 -1800);
FORCEPROP 1 LAST TOLERANCE 5%
J 0
(-1675 -1800);
DISPLAY 0.617021 (-1675 -1800);
PAINT SKYBLUE (-1675 -1800);
FORCEPROP 1 LAST PACK_TYPE 0402
J 0
(-1600 -1800);
DISPLAY 0.617021 (-1600 -1800);
PAINT SKYBLUE (-1600 -1800);
FORCEPROP 1 LAST WATTAGE 1/16W
J 0
(-1475 -1800);
DISPLAY 0.510638 (-1475 -1800);
PAINT SKYBLUE (-1475 -1800);
FORCEPROP 1 LAST PART_NUMBER G21497-005
J 0
(-1600 -1750);
DISPLAY 0.617021 (-1600 -1750);
PAINT BLUE (-1600 -1750);
FORCEPROP 2 LAST SEC 1
J 0
(-1550 -1625);
DISPLAY 0.680851 (-1550 -1625);
PAINT MONO (-1550 -1625);
DISPLAY INVISIBLE (-1550 -1625);
FORCEPROP 2 LAST SEC_TYPE 0402
J 0
(-1550 -1625);
DISPLAY 1.021277 (-1550 -1625);
PAINT ORANGE (-1550 -1625);
DISPLAY INVISIBLE (-1550 -1625);
FORCEPROP 2 LAST ROOM CPU0
J 0
(-1550 -1700);
PAINT PEACH (-1550 -1700);
DISPLAY INVISIBLE (-1550 -1700);
FORCEPROP 1 LAST MATERIAL CHIP
J 0
(-1350 -1950);
DISPLAY 0.510638 (-1350 -1950);
PAINT SKYBLUE (-1350 -1950);
DISPLAY INVISIBLE (-1350 -1950);
FORCEPROP 2 LAST BOM_COST PROC_SIDEBAND
J 0
(-1500 -1850);
PAINT MONO (-1500 -1850);
DISPLAY INVISIBLE (-1500 -1850);
FORCEPROP 2 LAST CDS_LIB mstr_discrete
J 0
(-1500 -1850);
DISPLAY 1.340426 (-1500 -1850);
PAINT ORANGE (-1500 -1850);
DISPLAY INVISIBLE (-1500 -1850);
FORCEPROP 1 LAST PATH I176
J 0
(-1550 -1700);
DISPLAY 0.978723 (-1550 -1700);
PAINT WHITE (-1550 -1700);
DISPLAY INVISIBLE (-1550 -1700);
FORCEPROP 2 LAST CDS_LOCATION R2W5
J 0
(-1975 -1850);
DISPLAY 0.617021 (-1975 -1850);
PAINT AQUA (-1975 -1850);
DISPLAY INVISIBLE (-1975 -1850);
FORCEADD OFFPAGE..2
R 2
(-6150 -3150);
FORCEPROP 2 LAST $XR0 245 
J 0
(-6405 -3150);
DISPLAY 0.638298 (-6405 -3150);
PAINT MONO (-6405 -3150);
FORCEPROP 2 LAST PATH I177
J 0
(-6400 -3100);
DISPLAY 1.021277 (-6400 -3100);
PAINT ORANGE (-6400 -3100);
DISPLAY INVISIBLE (-6400 -3100);
FORCEPROP 2 LAST CDS_LIB mstr_standard
J 2
(-6150 -3150);
PAINT MONO (-6150 -3150);
DISPLAY INVISIBLE (-6150 -3150);
FORCEPROP 1 LAST OFFPAGE TRUE
J 2
(-6475 -3275);
DISPLAY 0.872340 (-6475 -3275);
PAINT GREEN (-6475 -3275);
DISPLAY INVISIBLE (-6475 -3275);
FORCEPROP 1 LAST COMMENT_BODY TRUE
J 2
(-6105 -3245);
DISPLAY 0.872340 (-6105 -3245);
PAINT GREEN (-6105 -3245);
DISPLAY INVISIBLE (-6105 -3245);
FORCEADD RES..1
(-6450 -3250);
FORCEPROP 1 LAST PACK_TYPE 0402
J 0
(-6425 -3200);
DISPLAY 0.638298 (-6425 -3200);
PAINT SKYBLUE (-6425 -3200);
FORCEPROP 1 LAST LOCATION R9F33
J 0
(-6750 -3250);
DISPLAY 0.617021 (-6750 -3250);
PAINT AQUA (-6750 -3250);
FORCEPROP 1 LAST PART_NUMBER G21497-005
J 0
(-6775 -3300);
DISPLAY 0.617021 (-6775 -3300);
PAINT BLUE (-6775 -3300);
FORCEPROP 1 LAST WATTAGE 1/16W
J 0
(-6700 -3200);
DISPLAY 0.638298 (-6700 -3200);
PAINT SKYBLUE (-6700 -3200);
FORCEPROP 1 LASTPIN (-6350 -3250) $PN 2
J 0
(-6388 -3238);
DISPLAY 0.617021 (-6388 -3238);
PAINT ORANGE (-6388 -3238);
FORCEPROP 1 LAST MATERIAL CHIP
J 0
(-6325 -3250);
DISPLAY 0.617021 (-6325 -3250);
PAINT SKYBLUE (-6325 -3250);
FORCEPROP 1 LAST TOLERANCE 5%
J 0
(-6400 -3300);
DISPLAY 0.617021 (-6400 -3300);
PAINT SKYBLUE (-6400 -3300);
FORCEPROP 1 LAST VALUE 0.0
J 2
(-6475 -3300);
DISPLAY 0.617021 (-6475 -3300);
PAINT SKYBLUE (-6475 -3300);
FORCEPROP 1 LASTPIN (-6550 -3250) $PN 1
J 0
(-6538 -3238);
DISPLAY 0.617021 (-6538 -3238);
PAINT ORANGE (-6538 -3238);
FORCEPROP 1 LAST PATH I20
J 0
(-6500 -3100);
DISPLAY 0.978723 (-6500 -3100);
PAINT WHITE (-6500 -3100);
DISPLAY INVISIBLE (-6500 -3100);
FORCEPROP 0 LAST CDS_SEC 1
J 0
(-6325 -3200);
PAINT MONO (-6325 -3200);
DISPLAY INVISIBLE (-6325 -3200);
FORCEPROP 0 LAST BOM_COST SM_CONTROLLER
J 0
(-6500 -2950);
DISPLAY 1.021277 (-6500 -2950);
PAINT ORANGE (-6500 -2950);
DISPLAY INVISIBLE (-6500 -2950);
FORCEPROP 0 LAST ROOM BMC
J 0
(-6500 -3050);
DISPLAY 1.021277 (-6500 -3050);
PAINT ORANGE (-6500 -3050);
DISPLAY INVISIBLE (-6500 -3050);
FORCEPROP 2 LAST SEC_TYPE 0402
J 0
(-6500 -3050);
DISPLAY 1.021277 (-6500 -3050);
PAINT ORANGE (-6500 -3050);
DISPLAY INVISIBLE (-6500 -3050);
FORCEPROP 2 LAST SEC 1
J 0
(-6500 -3050);
DISPLAY 0.680851 (-6500 -3050);
PAINT MONO (-6500 -3050);
DISPLAY INVISIBLE (-6500 -3050);
FORCEPROP 2 LAST CDS_LIB mstr_discrete
J 0
(-6450 -3250);
PAINT ORANGE (-6450 -3250);
DISPLAY INVISIBLE (-6450 -3250);
FORCEPROP 2 LAST CDS_LOCATION R9F33
J 0
(-6850 -3250);
DISPLAY 0.617021 (-6850 -3250);
PAINT AQUA (-6850 -3250);
DISPLAY INVISIBLE (-6850 -3250);
FORCEADD OFFPAGE..6
(-7750 -3250);
FORCEPROP 2 LAST $XR0 166 
J 0
(-8030 -3250);
DISPLAY 0.638298 (-8030 -3250);
PAINT MONO (-8030 -3250);
FORCEPROP 1 LAST COMMENT_BODY TRUE
J 0
(-7650 -3325);
DISPLAY 0.872340 (-7650 -3325);
PAINT GREEN (-7650 -3325);
DISPLAY INVISIBLE (-7650 -3325);
FORCEPROP 1 LAST OFFPAGE TRUE
J 0
(-7425 -3375);
DISPLAY 0.872340 (-7425 -3375);
PAINT GREEN (-7425 -3375);
DISPLAY INVISIBLE (-7425 -3375);
FORCEPROP 2 LAST PATH I21
J 0
(-8025 -3200);
DISPLAY 1.021277 (-8025 -3200);
PAINT ORANGE (-8025 -3200);
DISPLAY INVISIBLE (-8025 -3200);
FORCEPROP 2 LAST CDS_LIB mstr_standard
J 0
(-7750 -3250);
PAINT ORANGE (-7750 -3250);
DISPLAY INVISIBLE (-7750 -3250);
FORCEADD RES..2
(-7650 -3425);
FORCEPROP 1 LASTPIN (-7650 -3325) $PN 1
J 0
(-7645 -3363);
DISPLAY 0.617021 (-7645 -3363);
PAINT ORANGE (-7645 -3363);
FORCEPROP 1 LASTPIN (-7650 -3525) $PN 2
J 0
(-7645 -3515);
DISPLAY 0.617021 (-7645 -3515);
PAINT ORANGE (-7645 -3515);
FORCEPROP 1 LAST PACK_TYPE 0402
J 0
(-7535 -3625);
DISPLAY 0.617021 (-7535 -3625);
PAINT SKYBLUE (-7535 -3625);
FORCEPROP 1 LAST MATERIAL EMPTY
J 0
(-7535 -3525);
DISPLAY 0.617021 (-7535 -3525);
PAINT RED (-7535 -3525);
FORCEPROP 1 LAST LOCATION R9F20
J 0
(-7530 -3325);
DISPLAY 0.617021 (-7530 -3325);
PAINT AQUA (-7530 -3325);
FORCEPROP 1 LAST VALUE 348
J 0
(-7530 -3375);
DISPLAY 0.617021 (-7530 -3375);
PAINT SKYBLUE (-7530 -3375);
FORCEPROP 1 LAST TOLERANCE 1%
J 0
(-7530 -3425);
DISPLAY 0.617021 (-7530 -3425);
PAINT SKYBLUE (-7530 -3425);
FORCEPROP 1 LAST WATTAGE 1/16W
J 0
(-7535 -3475);
DISPLAY 0.617021 (-7535 -3475);
PAINT SKYBLUE (-7535 -3475);
FORCEPROP 1 LAST PART_NUMBER G21796-340
J 0
(-7535 -3575);
DISPLAY 0.617021 (-7535 -3575);
PAINT BLUE (-7535 -3575);
FORCEPROP 1 LAST PATH I22
J 0
(-7600 -3250);
DISPLAY 0.978723 (-7600 -3250);
PAINT WHITE (-7600 -3250);
DISPLAY INVISIBLE (-7600 -3250);
FORCEPROP 0 LAST CDS_SEC 1
J 0
(-7625 -3225);
PAINT MONO (-7625 -3225);
DISPLAY INVISIBLE (-7625 -3225);
FORCEPROP 0 LAST BOM_COST SM_CONTROLLER
J 0
(-7600 -3100);
DISPLAY 1.021277 (-7600 -3100);
PAINT ORANGE (-7600 -3100);
DISPLAY INVISIBLE (-7600 -3100);
FORCEPROP 2 LAST SEC 1
J 0
(-7600 -3200);
DISPLAY 0.680851 (-7600 -3200);
PAINT MONO (-7600 -3200);
DISPLAY INVISIBLE (-7600 -3200);
FORCEPROP 2 LAST SEC_TYPE 0402
J 0
(-7600 -3200);
DISPLAY 1.021277 (-7600 -3200);
PAINT ORANGE (-7600 -3200);
DISPLAY INVISIBLE (-7600 -3200);
FORCEPROP 0 LAST ROOM BMC
J 0
(-7600 -3200);
DISPLAY 1.021277 (-7600 -3200);
PAINT ORANGE (-7600 -3200);
DISPLAY INVISIBLE (-7600 -3200);
FORCEPROP 2 LAST CDS_LOCATION R9F20
J 0
(-7605 -3300);
DISPLAY 0.617021 (-7605 -3300);
PAINT AQUA (-7605 -3300);
DISPLAY INVISIBLE (-7605 -3300);
FORCEPROP 2 LAST CDS_LIB mstr_discrete
J 0
(-7650 -3425);
PAINT ORANGE (-7650 -3425);
DISPLAY INVISIBLE (-7650 -3425);
FORCEADD GND..1
(-7650 -3625);
FORCEPROP 3 LASTPIN (-7650 -3575) SIG_NAME GND\g
J 0
(-7640 -3565);
DISPLAY 0.659574 (-7640 -3565);
PAINT MONO (-7640 -3565);
DISPLAY INVISIBLE (-7640 -3565);
FORCEPROP 1 LAST PATH I23
J 0
(-7575 -3625);
DISPLAY 0.872340 (-7575 -3625);
PAINT AQUA (-7575 -3625);
DISPLAY INVISIBLE (-7575 -3625);
FORCEPROP 1 LAST VOLTAGE 0.0V
J 0
(-7695 -3668);
DISPLAY 0.340426 (-7695 -3668);
PAINT SKYBLUE (-7695 -3668);
DISPLAY INVISIBLE (-7695 -3668);
FORCEPROP 1 LAST SIZE 1B
J 0
(-7575 -3675);
DISPLAY 0.872340 (-7575 -3675);
PAINT AQUA (-7575 -3675);
DISPLAY INVISIBLE (-7575 -3675);
FORCEPROP 2 LAST CDS_LIB mstr_symbols
J 0
(-7650 -3625);
PAINT ORANGE (-7650 -3625);
DISPLAY INVISIBLE (-7650 -3625);
FORCEPROP 1 LAST BODY_TYPE PLUMBING
J 0
(-7695 -3668);
DISPLAY 0.340426 (-7695 -3668);
PAINT GREEN (-7695 -3668);
DISPLAY INVISIBLE (-7695 -3668);
FORCEPROP 1 LAST HDL_POWER GND
J 0
(-7650 -3475);
DISPLAY 0.872340 (-7650 -3475);
PAINT GREEN (-7650 -3475);
DISPLAY INVISIBLE (-7650 -3475);
FORCEADD OFFPAGE..1
(-6150 -3350);
FORCEPROP 2 LAST $XR1 190 
J 0
(-6552 -3350);
DISPLAY 0.638298 (-6552 -3350);
PAINT MONO (-6552 -3350);
FORCEPROP 2 LAST $XR0 158 
J 0
(-6432 -3350);
DISPLAY 0.638298 (-6432 -3350);
PAINT MONO (-6432 -3350);
FORCEPROP 2 LAST CDS_LIB mstr_standard
J 0
(-6150 -3350);
PAINT ORANGE (-6150 -3350);
DISPLAY INVISIBLE (-6150 -3350);
FORCEPROP 2 LAST PATH I24
J 0
(-6400 -3300);
DISPLAY 1.021277 (-6400 -3300);
PAINT ORANGE (-6400 -3300);
DISPLAY INVISIBLE (-6400 -3300);
FORCEPROP 1 LAST OFFPAGE TRUE
J 0
(-5825 -3475);
DISPLAY 0.872340 (-5825 -3475);
PAINT GREEN (-5825 -3475);
DISPLAY INVISIBLE (-5825 -3475);
FORCEPROP 1 LAST COMMENT_BODY TRUE
J 0
(-6025 -3450);
DISPLAY 0.872340 (-6025 -3450);
PAINT GREEN (-6025 -3450);
DISPLAY INVISIBLE (-6025 -3450);
FORCEADD OFFPAGE..1
(-6650 -3450);
FORCEPROP 2 LAST $XR3 184 
J 0
(-7262 -3450);
DISPLAY 0.638298 (-7262 -3450);
PAINT MONO (-7262 -3450);
FORCEPROP 2 LAST $XR2 134 
J 0
(-7142 -3450);
DISPLAY 0.638298 (-7142 -3450);
PAINT MONO (-7142 -3450);
FORCEPROP 2 LAST $XR1 191 
J 0
(-7022 -3450);
DISPLAY 0.638298 (-7022 -3450);
PAINT MONO (-7022 -3450);
FORCEPROP 2 LAST $XR0 146 
J 0
(-6902 -3450);
DISPLAY 0.638298 (-6902 -3450);
PAINT MONO (-6902 -3450);
FORCEPROP 1 LAST COMMENT_BODY TRUE
J 0
(-6525 -3550);
DISPLAY 0.872340 (-6525 -3550);
PAINT GREEN (-6525 -3550);
DISPLAY INVISIBLE (-6525 -3550);
FORCEPROP 1 LAST OFFPAGE TRUE
J 0
(-6325 -3575);
DISPLAY 0.872340 (-6325 -3575);
PAINT GREEN (-6325 -3575);
DISPLAY INVISIBLE (-6325 -3575);
FORCEPROP 2 LAST PATH I25
J 0
(-6900 -3400);
DISPLAY 1.021277 (-6900 -3400);
PAINT ORANGE (-6900 -3400);
DISPLAY INVISIBLE (-6900 -3400);
FORCEPROP 2 LAST CDS_LIB mstr_standard
J 0
(-6650 -3450);
PAINT ORANGE (-6650 -3450);
DISPLAY INVISIBLE (-6650 -3450);
FORCEADD OFFPAGE..1
(-6650 -3550);
FORCEPROP 2 LAST $XR0 114 
J 0
(-6902 -3550);
DISPLAY 0.638298 (-6902 -3550);
PAINT MONO (-6902 -3550);
FORCEPROP 1 LAST COMMENT_BODY TRUE
J 0
(-6525 -3650);
DISPLAY 0.872340 (-6525 -3650);
PAINT GREEN (-6525 -3650);
DISPLAY INVISIBLE (-6525 -3650);
FORCEPROP 1 LAST OFFPAGE TRUE
J 0
(-6325 -3675);
DISPLAY 0.872340 (-6325 -3675);
PAINT GREEN (-6325 -3675);
DISPLAY INVISIBLE (-6325 -3675);
FORCEPROP 2 LAST PATH I26
J 0
(-6900 -3500);
DISPLAY 1.021277 (-6900 -3500);
PAINT ORANGE (-6900 -3500);
DISPLAY INVISIBLE (-6900 -3500);
FORCEPROP 2 LAST CDS_LIB mstr_standard
J 0
(-6650 -3550);
PAINT ORANGE (-6650 -3550);
DISPLAY INVISIBLE (-6650 -3550);
FORCEADD OFFPAGE..1
(-6650 -3600);
FORCEPROP 2 LAST $XR0 114 
J 0
(-6902 -3600);
DISPLAY 0.638298 (-6902 -3600);
PAINT MONO (-6902 -3600);
FORCEPROP 1 LAST COMMENT_BODY TRUE
J 0
(-6525 -3700);
DISPLAY 0.872340 (-6525 -3700);
PAINT GREEN (-6525 -3700);
DISPLAY INVISIBLE (-6525 -3700);
FORCEPROP 1 LAST OFFPAGE TRUE
J 0
(-6325 -3725);
DISPLAY 0.872340 (-6325 -3725);
PAINT GREEN (-6325 -3725);
DISPLAY INVISIBLE (-6325 -3725);
FORCEPROP 2 LAST CDS_LIB mstr_standard
J 0
(-6650 -3600);
PAINT ORANGE (-6650 -3600);
DISPLAY INVISIBLE (-6650 -3600);
FORCEPROP 2 LAST PATH I27
J 0
(-6900 -3550);
DISPLAY 1.021277 (-6900 -3550);
PAINT ORANGE (-6900 -3550);
DISPLAY INVISIBLE (-6900 -3550);
FORCEADD OFFPAGE..1
(-6650 -3700);
FORCEPROP 2 LAST $XR0 116 
J 0
(-6902 -3700);
DISPLAY 0.638298 (-6902 -3700);
PAINT MONO (-6902 -3700);
FORCEPROP 1 LAST COMMENT_BODY TRUE
J 0
(-6525 -3800);
DISPLAY 0.872340 (-6525 -3800);
PAINT GREEN (-6525 -3800);
DISPLAY INVISIBLE (-6525 -3800);
FORCEPROP 1 LAST OFFPAGE TRUE
J 0
(-6325 -3825);
DISPLAY 0.872340 (-6325 -3825);
PAINT GREEN (-6325 -3825);
DISPLAY INVISIBLE (-6325 -3825);
FORCEPROP 2 LAST CDS_LIB mstr_standard
J 0
(-6650 -3700);
PAINT ORANGE (-6650 -3700);
DISPLAY INVISIBLE (-6650 -3700);
FORCEPROP 2 LAST PATH I28
J 0
(-6900 -3650);
DISPLAY 1.021277 (-6900 -3650);
PAINT ORANGE (-6900 -3650);
DISPLAY INVISIBLE (-6900 -3650);
FORCEADD OFFPAGE..1
(-6650 -3750);
FORCEPROP 2 LAST $XR0 116 
J 0
(-6902 -3750);
DISPLAY 0.638298 (-6902 -3750);
PAINT MONO (-6902 -3750);
FORCEPROP 1 LAST COMMENT_BODY TRUE
J 0
(-6525 -3850);
DISPLAY 0.872340 (-6525 -3850);
PAINT GREEN (-6525 -3850);
DISPLAY INVISIBLE (-6525 -3850);
FORCEPROP 1 LAST OFFPAGE TRUE
J 0
(-6325 -3875);
DISPLAY 0.872340 (-6325 -3875);
PAINT GREEN (-6325 -3875);
DISPLAY INVISIBLE (-6325 -3875);
FORCEPROP 2 LAST PATH I29
J 0
(-6900 -3700);
DISPLAY 1.021277 (-6900 -3700);
PAINT ORANGE (-6900 -3700);
DISPLAY INVISIBLE (-6900 -3700);
FORCEPROP 2 LAST CDS_LIB mstr_standard
J 0
(-6650 -3750);
PAINT ORANGE (-6650 -3750);
DISPLAY INVISIBLE (-6650 -3750);
FORCEADD RES..2
(-5450 -4150);
FORCEPROP 0 LAST GROUP AST2520
J 0
(-5400 -4450);
DISPLAY 0.638298 (-5400 -4450);
PAINT BROWN (-5400 -4450);
DISPLAY BOTH (-5400 -4450);
FORCEPROP 1 LAST PACK_TYPE 0402
J 0
(-5410 -4325);
DISPLAY 0.617021 (-5410 -4325);
PAINT SKYBLUE (-5410 -4325);
FORCEPROP 1 LASTPIN (-5450 -4250) $PN 2
J 0
(-5445 -4240);
DISPLAY 0.617021 (-5445 -4240);
PAINT ORANGE (-5445 -4240);
FORCEPROP 1 LAST WATTAGE 1/16W
J 0
(-5410 -4175);
DISPLAY 0.617021 (-5410 -4175);
PAINT SKYBLUE (-5410 -4175);
FORCEPROP 1 LASTPIN (-5450 -4050) $PN 1
J 0
(-5445 -4088);
DISPLAY 0.617021 (-5445 -4088);
PAINT ORANGE (-5445 -4088);
FORCEPROP 1 LAST MATERIAL CHIP
J 0
(-5410 -4225);
DISPLAY 0.617021 (-5410 -4225);
PAINT SKYBLUE (-5410 -4225);
FORCEPROP 1 LAST TOLERANCE 1%
J 0
(-5405 -4125);
DISPLAY 0.617021 (-5405 -4125);
PAINT SKYBLUE (-5405 -4125);
FORCEPROP 1 LAST VALUE 100.0K
J 0
(-5405 -4075);
DISPLAY 0.617021 (-5405 -4075);
PAINT SKYBLUE (-5405 -4075);
FORCEPROP 1 LAST LOCATION R25W61
J 0
(-5405 -4025);
DISPLAY 0.617021 (-5405 -4025);
PAINT AQUA (-5405 -4025);
FORCEPROP 1 LAST PART_NUMBER G21796-010
J 0
(-5410 -4275);
DISPLAY 0.617021 (-5410 -4275);
PAINT BLUE (-5410 -4275);
FORCEPROP 1 LAST PATH I30
J 0
(-5400 -3975);
DISPLAY 0.978723 (-5400 -3975);
PAINT WHITE (-5400 -3975);
DISPLAY INVISIBLE (-5400 -3975);
FORCEPROP 0 LAST ROOM BMC
J 0
(-5400 -3925);
DISPLAY 0.617021 (-5400 -3925);
PAINT ORANGE (-5400 -3925);
DISPLAY INVISIBLE (-5400 -3925);
FORCEPROP 0 LAST BOM_COST SM_CONTROLLER
J 0
(-5400 -3825);
DISPLAY 1.021277 (-5400 -3825);
PAINT ORANGE (-5400 -3825);
DISPLAY INVISIBLE (-5400 -3825);
FORCEPROP 2 LAST SEC_TYPE 0402
J 0
(-5400 -3925);
DISPLAY 1.021277 (-5400 -3925);
PAINT ORANGE (-5400 -3925);
DISPLAY INVISIBLE (-5400 -3925);
FORCEPROP 2 LAST SEC 1
J 0
(-5400 -3925);
DISPLAY 0.680851 (-5400 -3925);
PAINT MONO (-5400 -3925);
DISPLAY INVISIBLE (-5400 -3925);
FORCEPROP 2 LAST CDS_LIB mstr_discrete
J 0
(-5450 -4150);
PAINT ORANGE (-5450 -4150);
DISPLAY INVISIBLE (-5450 -4150);
FORCEPROP 0 LAST CDS_SEC 1
J 0
(-5400 -3975);
PAINT MONO (-5400 -3975);
DISPLAY INVISIBLE (-5400 -3975);
FORCEPROP 2 LAST CDS_LOCATION R25W61
J 0
(-5405 -4025);
DISPLAY 0.617021 (-5405 -4025);
PAINT AQUA (-5405 -4025);
DISPLAY INVISIBLE (-5405 -4025);
FORCEADD RES..2
(-5200 -4150);
FORCEPROP 0 LAST GROUP AST2520
J 0
(-5150 -4400);
DISPLAY 0.638298 (-5150 -4400);
PAINT BROWN (-5150 -4400);
DISPLAY BOTH (-5150 -4400);
FORCEPROP 1 LASTPIN (-5200 -4050) $PN 1
J 0
(-5195 -4088);
DISPLAY 0.617021 (-5195 -4088);
PAINT ORANGE (-5195 -4088);
FORCEPROP 1 LAST PACK_TYPE 0402
J 0
(-5160 -4325);
DISPLAY 0.617021 (-5160 -4325);
PAINT SKYBLUE (-5160 -4325);
FORCEPROP 1 LAST PART_NUMBER G21796-010
J 0
(-5160 -4275);
DISPLAY 0.617021 (-5160 -4275);
PAINT BLUE (-5160 -4275);
FORCEPROP 1 LAST TOLERANCE 1%
J 0
(-5155 -4125);
DISPLAY 0.617021 (-5155 -4125);
PAINT SKYBLUE (-5155 -4125);
FORCEPROP 1 LAST VALUE 100.0K
J 0
(-5155 -4075);
DISPLAY 0.617021 (-5155 -4075);
PAINT SKYBLUE (-5155 -4075);
FORCEPROP 1 LAST LOCATION R25W62
J 0
(-5155 -4025);
DISPLAY 0.617021 (-5155 -4025);
PAINT AQUA (-5155 -4025);
FORCEPROP 1 LASTPIN (-5200 -4250) $PN 2
J 0
(-5195 -4240);
DISPLAY 0.617021 (-5195 -4240);
PAINT ORANGE (-5195 -4240);
FORCEPROP 1 LAST MATERIAL CHIP
J 0
(-5160 -4225);
DISPLAY 0.617021 (-5160 -4225);
PAINT SKYBLUE (-5160 -4225);
FORCEPROP 1 LAST WATTAGE 1/16W
J 0
(-5160 -4175);
DISPLAY 0.617021 (-5160 -4175);
PAINT SKYBLUE (-5160 -4175);
FORCEPROP 0 LAST CDS_SEC 1
J 0
(-5150 -3975);
PAINT MONO (-5150 -3975);
DISPLAY INVISIBLE (-5150 -3975);
FORCEPROP 2 LAST CDS_LIB mstr_discrete
J 0
(-5200 -4150);
PAINT ORANGE (-5200 -4150);
DISPLAY INVISIBLE (-5200 -4150);
FORCEPROP 2 LAST SEC 1
J 0
(-5150 -3925);
DISPLAY 0.680851 (-5150 -3925);
PAINT MONO (-5150 -3925);
DISPLAY INVISIBLE (-5150 -3925);
FORCEPROP 2 LAST SEC_TYPE 0402
J 0
(-5150 -3925);
DISPLAY 1.021277 (-5150 -3925);
PAINT ORANGE (-5150 -3925);
DISPLAY INVISIBLE (-5150 -3925);
FORCEPROP 0 LAST BOM_COST SM_CONTROLLER
J 0
(-5150 -3825);
DISPLAY 1.021277 (-5150 -3825);
PAINT ORANGE (-5150 -3825);
DISPLAY INVISIBLE (-5150 -3825);
FORCEPROP 0 LAST ROOM BMC
J 0
(-5150 -3925);
DISPLAY 0.617021 (-5150 -3925);
PAINT ORANGE (-5150 -3925);
DISPLAY INVISIBLE (-5150 -3925);
FORCEPROP 1 LAST PATH I31
J 0
(-5150 -3975);
DISPLAY 0.978723 (-5150 -3975);
PAINT WHITE (-5150 -3975);
DISPLAY INVISIBLE (-5150 -3975);
FORCEPROP 2 LAST CDS_LOCATION R25W62
J 0
(-5155 -4025);
DISPLAY 0.617021 (-5155 -4025);
PAINT AQUA (-5155 -4025);
DISPLAY INVISIBLE (-5155 -4025);
FORCEADD GND..1
(-5200 -4350);
FORCEPROP 3 LASTPIN (-5200 -4300) SIG_NAME GND\g
J 0
(-5190 -4290);
DISPLAY 0.659574 (-5190 -4290);
PAINT MONO (-5190 -4290);
DISPLAY INVISIBLE (-5190 -4290);
FORCEPROP 1 LAST HDL_POWER GND
J 0
(-5200 -4200);
DISPLAY 0.872340 (-5200 -4200);
PAINT GREEN (-5200 -4200);
DISPLAY INVISIBLE (-5200 -4200);
FORCEPROP 1 LAST BODY_TYPE PLUMBING
J 0
(-5245 -4393);
DISPLAY 0.340426 (-5245 -4393);
PAINT GREEN (-5245 -4393);
DISPLAY INVISIBLE (-5245 -4393);
FORCEPROP 1 LAST PATH I32
J 0
(-5125 -4350);
DISPLAY 0.872340 (-5125 -4350);
PAINT AQUA (-5125 -4350);
DISPLAY INVISIBLE (-5125 -4350);
FORCEPROP 1 LAST SIZE 1B
J 0
(-5125 -4400);
DISPLAY 0.872340 (-5125 -4400);
PAINT AQUA (-5125 -4400);
DISPLAY INVISIBLE (-5125 -4400);
FORCEPROP 1 LAST VOLTAGE 0.0V
J 0
(-5245 -4393);
DISPLAY 0.340426 (-5245 -4393);
PAINT SKYBLUE (-5245 -4393);
DISPLAY INVISIBLE (-5245 -4393);
FORCEPROP 2 LAST CDS_LIB mstr_symbols
J 0
(-5200 -4350);
PAINT ORANGE (-5200 -4350);
DISPLAY INVISIBLE (-5200 -4350);
FORCEADD GND..1
(-5450 -4350);
FORCEPROP 3 LASTPIN (-5450 -4300) SIG_NAME GND\g
J 0
(-5440 -4290);
DISPLAY 0.659574 (-5440 -4290);
PAINT MONO (-5440 -4290);
DISPLAY INVISIBLE (-5440 -4290);
FORCEPROP 1 LAST HDL_POWER GND
J 0
(-5450 -4200);
DISPLAY 0.872340 (-5450 -4200);
PAINT GREEN (-5450 -4200);
DISPLAY INVISIBLE (-5450 -4200);
FORCEPROP 1 LAST BODY_TYPE PLUMBING
J 0
(-5495 -4393);
DISPLAY 0.340426 (-5495 -4393);
PAINT GREEN (-5495 -4393);
DISPLAY INVISIBLE (-5495 -4393);
FORCEPROP 1 LAST PATH I33
J 0
(-5375 -4350);
DISPLAY 0.872340 (-5375 -4350);
PAINT AQUA (-5375 -4350);
DISPLAY INVISIBLE (-5375 -4350);
FORCEPROP 1 LAST SIZE 1B
J 0
(-5375 -4400);
DISPLAY 0.872340 (-5375 -4400);
PAINT AQUA (-5375 -4400);
DISPLAY INVISIBLE (-5375 -4400);
FORCEPROP 1 LAST VOLTAGE 0.0V
J 0
(-5495 -4393);
DISPLAY 0.340426 (-5495 -4393);
PAINT SKYBLUE (-5495 -4393);
DISPLAY INVISIBLE (-5495 -4393);
FORCEPROP 2 LAST CDS_LIB mstr_symbols
J 0
(-5450 -4350);
PAINT ORANGE (-5450 -4350);
DISPLAY INVISIBLE (-5450 -4350);
FORCEADD RES..2
(-5700 -4150);
FORCEPROP 0 LAST GROUP AST2520
J 0
(-5650 -4400);
DISPLAY 0.638298 (-5650 -4400);
PAINT BROWN (-5650 -4400);
DISPLAY BOTH (-5650 -4400);
FORCEPROP 1 LAST LOCATION R25W60
J 0
(-5655 -4025);
DISPLAY 0.617021 (-5655 -4025);
PAINT AQUA (-5655 -4025);
FORCEPROP 1 LAST VALUE 100.0K
J 0
(-5655 -4075);
DISPLAY 0.617021 (-5655 -4075);
PAINT SKYBLUE (-5655 -4075);
FORCEPROP 1 LAST WATTAGE 1/16W
J 0
(-5660 -4175);
DISPLAY 0.617021 (-5660 -4175);
PAINT SKYBLUE (-5660 -4175);
FORCEPROP 1 LASTPIN (-5700 -4050) $PN 1
J 0
(-5695 -4088);
DISPLAY 0.617021 (-5695 -4088);
PAINT ORANGE (-5695 -4088);
FORCEPROP 1 LASTPIN (-5700 -4250) $PN 2
J 0
(-5695 -4240);
DISPLAY 0.617021 (-5695 -4240);
PAINT ORANGE (-5695 -4240);
FORCEPROP 1 LAST MATERIAL CHIP
J 0
(-5660 -4225);
DISPLAY 0.617021 (-5660 -4225);
PAINT SKYBLUE (-5660 -4225);
FORCEPROP 1 LAST TOLERANCE 1%
J 0
(-5655 -4125);
DISPLAY 0.617021 (-5655 -4125);
PAINT SKYBLUE (-5655 -4125);
FORCEPROP 1 LAST PART_NUMBER G21796-010
J 0
(-5660 -4275);
DISPLAY 0.617021 (-5660 -4275);
PAINT BLUE (-5660 -4275);
FORCEPROP 1 LAST PACK_TYPE 0402
J 0
(-5660 -4325);
DISPLAY 0.617021 (-5660 -4325);
PAINT SKYBLUE (-5660 -4325);
FORCEPROP 1 LAST PATH I34
J 0
(-5650 -3975);
DISPLAY 0.978723 (-5650 -3975);
PAINT WHITE (-5650 -3975);
DISPLAY INVISIBLE (-5650 -3975);
FORCEPROP 0 LAST BOM_COST SM_CONTROLLER
J 0
(-5650 -3825);
DISPLAY 1.021277 (-5650 -3825);
PAINT ORANGE (-5650 -3825);
DISPLAY INVISIBLE (-5650 -3825);
FORCEPROP 0 LAST ROOM BMC
J 0
(-5650 -3925);
DISPLAY 0.617021 (-5650 -3925);
PAINT ORANGE (-5650 -3925);
DISPLAY INVISIBLE (-5650 -3925);
FORCEPROP 2 LAST SEC_TYPE 0402
J 0
(-5650 -3925);
DISPLAY 1.021277 (-5650 -3925);
PAINT ORANGE (-5650 -3925);
DISPLAY INVISIBLE (-5650 -3925);
FORCEPROP 2 LAST SEC 1
J 0
(-5650 -3925);
DISPLAY 0.680851 (-5650 -3925);
PAINT MONO (-5650 -3925);
DISPLAY INVISIBLE (-5650 -3925);
FORCEPROP 2 LAST CDS_LIB mstr_discrete
J 0
(-5700 -4150);
PAINT ORANGE (-5700 -4150);
DISPLAY INVISIBLE (-5700 -4150);
FORCEPROP 0 LAST CDS_SEC 1
J 0
(-5650 -3975);
PAINT MONO (-5650 -3975);
DISPLAY INVISIBLE (-5650 -3975);
FORCEPROP 2 LAST CDS_LOCATION R25W60
J 0
(-5655 -4025);
DISPLAY 0.617021 (-5655 -4025);
PAINT AQUA (-5655 -4025);
DISPLAY INVISIBLE (-5655 -4025);
FORCEADD GND..1
(-5700 -4350);
FORCEPROP 3 LASTPIN (-5700 -4300) SIG_NAME GND\g
J 0
(-5690 -4290);
DISPLAY 0.659574 (-5690 -4290);
PAINT MONO (-5690 -4290);
DISPLAY INVISIBLE (-5690 -4290);
FORCEPROP 1 LAST HDL_POWER GND
J 0
(-5700 -4200);
DISPLAY 0.872340 (-5700 -4200);
PAINT GREEN (-5700 -4200);
DISPLAY INVISIBLE (-5700 -4200);
FORCEPROP 1 LAST BODY_TYPE PLUMBING
J 0
(-5745 -4393);
DISPLAY 0.340426 (-5745 -4393);
PAINT GREEN (-5745 -4393);
DISPLAY INVISIBLE (-5745 -4393);
FORCEPROP 1 LAST PATH I35
J 0
(-5625 -4350);
DISPLAY 0.872340 (-5625 -4350);
PAINT AQUA (-5625 -4350);
DISPLAY INVISIBLE (-5625 -4350);
FORCEPROP 1 LAST SIZE 1B
J 0
(-5625 -4400);
DISPLAY 0.872340 (-5625 -4400);
PAINT AQUA (-5625 -4400);
DISPLAY INVISIBLE (-5625 -4400);
FORCEPROP 2 LAST CDS_LIB mstr_symbols
J 0
(-5700 -4350);
PAINT ORANGE (-5700 -4350);
DISPLAY INVISIBLE (-5700 -4350);
FORCEPROP 1 LAST VOLTAGE 0.0V
J 0
(-5745 -4393);
DISPLAY 0.340426 (-5745 -4393);
PAINT SKYBLUE (-5745 -4393);
DISPLAY INVISIBLE (-5745 -4393);
FORCEADD RES..2
(-5950 -4150);
FORCEPROP 0 LAST GROUP AST2520
J 0
(-5900 -4450);
DISPLAY 0.638298 (-5900 -4450);
PAINT BROWN (-5900 -4450);
DISPLAY BOTH (-5900 -4450);
FORCEPROP 1 LAST WATTAGE 1/16W
J 0
(-5910 -4175);
DISPLAY 0.617021 (-5910 -4175);
PAINT SKYBLUE (-5910 -4175);
FORCEPROP 1 LAST PART_NUMBER G21796-010
J 0
(-5910 -4275);
DISPLAY 0.617021 (-5910 -4275);
PAINT BLUE (-5910 -4275);
FORCEPROP 1 LAST PACK_TYPE 0402
J 0
(-5910 -4325);
DISPLAY 0.617021 (-5910 -4325);
PAINT SKYBLUE (-5910 -4325);
FORCEPROP 1 LAST LOCATION R25W64
J 0
(-5905 -4025);
DISPLAY 0.617021 (-5905 -4025);
PAINT AQUA (-5905 -4025);
FORCEPROP 1 LAST TOLERANCE 1%
J 0
(-5905 -4125);
DISPLAY 0.617021 (-5905 -4125);
PAINT SKYBLUE (-5905 -4125);
FORCEPROP 1 LASTPIN (-5950 -4250) $PN 2
J 0
(-5945 -4240);
DISPLAY 0.617021 (-5945 -4240);
PAINT ORANGE (-5945 -4240);
FORCEPROP 1 LAST MATERIAL CHIP
J 0
(-5910 -4225);
DISPLAY 0.617021 (-5910 -4225);
PAINT SKYBLUE (-5910 -4225);
FORCEPROP 1 LAST VALUE 100.0K
J 0
(-5905 -4075);
DISPLAY 0.617021 (-5905 -4075);
PAINT SKYBLUE (-5905 -4075);
FORCEPROP 1 LASTPIN (-5950 -4050) $PN 1
J 0
(-5945 -4088);
DISPLAY 0.617021 (-5945 -4088);
PAINT ORANGE (-5945 -4088);
FORCEPROP 1 LAST PATH I36
J 0
(-5900 -3975);
DISPLAY 0.978723 (-5900 -3975);
PAINT WHITE (-5900 -3975);
DISPLAY INVISIBLE (-5900 -3975);
FORCEPROP 0 LAST ROOM BMC
J 0
(-5900 -3925);
DISPLAY 0.617021 (-5900 -3925);
PAINT ORANGE (-5900 -3925);
DISPLAY INVISIBLE (-5900 -3925);
FORCEPROP 0 LAST BOM_COST SM_CONTROLLER
J 0
(-5900 -3825);
DISPLAY 1.021277 (-5900 -3825);
PAINT ORANGE (-5900 -3825);
DISPLAY INVISIBLE (-5900 -3825);
FORCEPROP 2 LAST SEC 1
J 0
(-5900 -3925);
DISPLAY 0.680851 (-5900 -3925);
PAINT MONO (-5900 -3925);
DISPLAY INVISIBLE (-5900 -3925);
FORCEPROP 2 LAST SEC_TYPE 0402
J 0
(-5900 -3925);
DISPLAY 1.021277 (-5900 -3925);
PAINT ORANGE (-5900 -3925);
DISPLAY INVISIBLE (-5900 -3925);
FORCEPROP 2 LAST CDS_LIB mstr_discrete
J 0
(-5950 -4150);
PAINT ORANGE (-5950 -4150);
DISPLAY INVISIBLE (-5950 -4150);
FORCEPROP 0 LAST CDS_SEC 1
J 0
(-5900 -3975);
PAINT MONO (-5900 -3975);
DISPLAY INVISIBLE (-5900 -3975);
FORCEPROP 2 LAST CDS_LOCATION R25W64
J 0
(-5905 -4025);
DISPLAY 0.617021 (-5905 -4025);
PAINT AQUA (-5905 -4025);
DISPLAY INVISIBLE (-5905 -4025);
FORCEADD GND..1
(-5950 -4350);
FORCEPROP 3 LASTPIN (-5950 -4300) SIG_NAME GND\g
J 0
(-5940 -4290);
DISPLAY 0.659574 (-5940 -4290);
PAINT MONO (-5940 -4290);
DISPLAY INVISIBLE (-5940 -4290);
FORCEPROP 1 LAST HDL_POWER GND
J 0
(-5950 -4200);
DISPLAY 0.872340 (-5950 -4200);
PAINT GREEN (-5950 -4200);
DISPLAY INVISIBLE (-5950 -4200);
FORCEPROP 1 LAST BODY_TYPE PLUMBING
J 0
(-5995 -4393);
DISPLAY 0.340426 (-5995 -4393);
PAINT GREEN (-5995 -4393);
DISPLAY INVISIBLE (-5995 -4393);
FORCEPROP 1 LAST PATH I37
J 0
(-5875 -4350);
DISPLAY 0.872340 (-5875 -4350);
PAINT AQUA (-5875 -4350);
DISPLAY INVISIBLE (-5875 -4350);
FORCEPROP 1 LAST SIZE 1B
J 0
(-5875 -4400);
DISPLAY 0.872340 (-5875 -4400);
PAINT AQUA (-5875 -4400);
DISPLAY INVISIBLE (-5875 -4400);
FORCEPROP 1 LAST VOLTAGE 0.0V
J 0
(-5995 -4393);
DISPLAY 0.340426 (-5995 -4393);
PAINT SKYBLUE (-5995 -4393);
DISPLAY INVISIBLE (-5995 -4393);
FORCEPROP 2 LAST CDS_LIB mstr_symbols
J 0
(-5950 -4350);
PAINT ORANGE (-5950 -4350);
DISPLAY INVISIBLE (-5950 -4350);
FORCEADD RES..2
(-6200 -4150);
FORCEPROP 0 LAST GROUP AST2520
J 0
(-6150 -4400);
DISPLAY 0.638298 (-6150 -4400);
PAINT BROWN (-6150 -4400);
DISPLAY BOTH (-6150 -4400);
FORCEPROP 1 LASTPIN (-6200 -4050) $PN 1
J 0
(-6195 -4088);
DISPLAY 0.617021 (-6195 -4088);
PAINT ORANGE (-6195 -4088);
FORCEPROP 1 LASTPIN (-6200 -4250) $PN 2
J 0
(-6195 -4240);
DISPLAY 0.617021 (-6195 -4240);
PAINT ORANGE (-6195 -4240);
FORCEPROP 1 LAST PACK_TYPE 0402
J 0
(-6160 -4325);
DISPLAY 0.617021 (-6160 -4325);
PAINT SKYBLUE (-6160 -4325);
FORCEPROP 1 LAST PART_NUMBER G21796-010
J 0
(-6160 -4275);
DISPLAY 0.617021 (-6160 -4275);
PAINT BLUE (-6160 -4275);
FORCEPROP 1 LAST MATERIAL CHIP
J 0
(-6160 -4225);
DISPLAY 0.617021 (-6160 -4225);
PAINT SKYBLUE (-6160 -4225);
FORCEPROP 1 LAST WATTAGE 1/16W
J 0
(-6160 -4175);
DISPLAY 0.617021 (-6160 -4175);
PAINT SKYBLUE (-6160 -4175);
FORCEPROP 1 LAST TOLERANCE 1%
J 0
(-6155 -4125);
DISPLAY 0.617021 (-6155 -4125);
PAINT SKYBLUE (-6155 -4125);
FORCEPROP 1 LAST VALUE 100.0K
J 0
(-6155 -4075);
DISPLAY 0.617021 (-6155 -4075);
PAINT SKYBLUE (-6155 -4075);
FORCEPROP 1 LAST LOCATION R25W65
J 0
(-6155 -4025);
DISPLAY 0.617021 (-6155 -4025);
PAINT AQUA (-6155 -4025);
FORCEPROP 0 LAST CDS_SEC 1
J 0
(-6150 -3975);
PAINT MONO (-6150 -3975);
DISPLAY INVISIBLE (-6150 -3975);
FORCEPROP 2 LAST CDS_LIB mstr_discrete
J 0
(-6200 -4150);
PAINT ORANGE (-6200 -4150);
DISPLAY INVISIBLE (-6200 -4150);
FORCEPROP 2 LAST SEC_TYPE 0402
J 0
(-6150 -3925);
DISPLAY 1.021277 (-6150 -3925);
PAINT ORANGE (-6150 -3925);
DISPLAY INVISIBLE (-6150 -3925);
FORCEPROP 2 LAST SEC 1
J 0
(-6150 -3925);
DISPLAY 0.680851 (-6150 -3925);
PAINT MONO (-6150 -3925);
DISPLAY INVISIBLE (-6150 -3925);
FORCEPROP 0 LAST BOM_COST SM_CONTROLLER
J 0
(-6150 -3825);
DISPLAY 1.021277 (-6150 -3825);
PAINT ORANGE (-6150 -3825);
DISPLAY INVISIBLE (-6150 -3825);
FORCEPROP 0 LAST ROOM BMC
J 0
(-6150 -3925);
DISPLAY 0.617021 (-6150 -3925);
PAINT ORANGE (-6150 -3925);
DISPLAY INVISIBLE (-6150 -3925);
FORCEPROP 1 LAST PATH I38
J 0
(-6150 -3975);
DISPLAY 0.978723 (-6150 -3975);
PAINT WHITE (-6150 -3975);
DISPLAY INVISIBLE (-6150 -3975);
FORCEPROP 2 LAST CDS_LOCATION R25W65
J 0
(-6155 -4025);
DISPLAY 0.617021 (-6155 -4025);
PAINT AQUA (-6155 -4025);
DISPLAY INVISIBLE (-6155 -4025);
FORCEADD GND..1
(-6200 -4350);
FORCEPROP 3 LASTPIN (-6200 -4300) SIG_NAME GND\g
J 0
(-6190 -4290);
DISPLAY 0.659574 (-6190 -4290);
PAINT MONO (-6190 -4290);
DISPLAY INVISIBLE (-6190 -4290);
FORCEPROP 1 LAST HDL_POWER GND
J 0
(-6200 -4200);
DISPLAY 0.872340 (-6200 -4200);
PAINT GREEN (-6200 -4200);
DISPLAY INVISIBLE (-6200 -4200);
FORCEPROP 1 LAST BODY_TYPE PLUMBING
J 0
(-6245 -4393);
DISPLAY 0.340426 (-6245 -4393);
PAINT GREEN (-6245 -4393);
DISPLAY INVISIBLE (-6245 -4393);
FORCEPROP 1 LAST PATH I39
J 0
(-6125 -4350);
DISPLAY 0.872340 (-6125 -4350);
PAINT AQUA (-6125 -4350);
DISPLAY INVISIBLE (-6125 -4350);
FORCEPROP 1 LAST SIZE 1B
J 0
(-6125 -4400);
DISPLAY 0.872340 (-6125 -4400);
PAINT AQUA (-6125 -4400);
DISPLAY INVISIBLE (-6125 -4400);
FORCEPROP 1 LAST VOLTAGE 0.0V
J 0
(-6245 -4393);
DISPLAY 0.340426 (-6245 -4393);
PAINT SKYBLUE (-6245 -4393);
DISPLAY INVISIBLE (-6245 -4393);
FORCEPROP 2 LAST CDS_LIB mstr_symbols
J 0
(-6200 -4350);
PAINT ORANGE (-6200 -4350);
DISPLAY INVISIBLE (-6200 -4350);
FORCEADD OFFPAGE..1
(-6150 -2450);
FORCEPROP 2 LAST $XR1 133 
J 0
(-6552 -2450);
DISPLAY 0.638298 (-6552 -2450);
PAINT MONO (-6552 -2450);
FORCEPROP 2 LAST $XR0 120 
J 0
(-6432 -2450);
DISPLAY 0.638298 (-6432 -2450);
PAINT MONO (-6432 -2450);
FORCEPROP 2 LAST BOM_COST SM_CONTROLLER
J 0
(-5700 -2400);
PAINT MONO (-5700 -2400);
DISPLAY INVISIBLE (-5700 -2400);
FORCEPROP 2 LAST ROOM BMC
J 0
(-6400 -2375);
DISPLAY 1.361702 (-6400 -2375);
PAINT ORANGE (-6400 -2375);
DISPLAY INVISIBLE (-6400 -2375);
FORCEPROP 2 LAST PATH I4
J 0
(-6100 -2375);
DISPLAY 1.021277 (-6100 -2375);
PAINT ORANGE (-6100 -2375);
DISPLAY INVISIBLE (-6100 -2375);
FORCEPROP 2 LAST CDS_LIB mstr_standard
J 0
(-6150 -2450);
PAINT MONO (-6150 -2450);
DISPLAY INVISIBLE (-6150 -2450);
FORCEPROP 1 LAST OFFPAGE TRUE
J 0
(-5825 -2575);
DISPLAY 0.872340 (-5825 -2575);
PAINT GREEN (-5825 -2575);
DISPLAY INVISIBLE (-5825 -2575);
FORCEPROP 1 LAST COMMENT_BODY TRUE
J 0
(-6025 -2550);
DISPLAY 0.872340 (-6025 -2550);
PAINT GREEN (-6025 -2550);
DISPLAY INVISIBLE (-6025 -2550);
FORCEADD OFFPAGE..2
(-800 -3100);
FORCEPROP 2 LAST $XR2 158 
J 0
(-611 -3136);
DISPLAY 0.638298 (-611 -3136);
PAINT MONO (-611 -3136);
FORCEPROP 2 LAST $XR1 190 
J 0
(-491 -3100);
DISPLAY 0.638298 (-491 -3100);
PAINT MONO (-491 -3100);
FORCEPROP 2 LAST $XR0 150 
J 0
(-611 -3100);
DISPLAY 0.638298 (-611 -3100);
PAINT MONO (-611 -3100);
FORCEPROP 2 LAST PATH I41
J 0
(-625 -3025);
DISPLAY 1.021277 (-625 -3025);
PAINT ORANGE (-625 -3025);
DISPLAY INVISIBLE (-625 -3025);
FORCEPROP 2 LAST CDS_LIB mstr_standard
J 0
(-800 -3100);
PAINT MONO (-800 -3100);
DISPLAY INVISIBLE (-800 -3100);
FORCEPROP 1 LAST OFFPAGE TRUE
J 0
(-475 -3225);
DISPLAY 0.872340 (-475 -3225);
PAINT GREEN (-475 -3225);
DISPLAY INVISIBLE (-475 -3225);
FORCEPROP 1 LAST COMMENT_BODY TRUE
J 0
(-845 -3195);
DISPLAY 0.872340 (-845 -3195);
PAINT GREEN (-845 -3195);
DISPLAY INVISIBLE (-845 -3195);
FORCEADD OFFPAGE..2
(-750 -3900);
FORCEPROP 2 LAST $XR0 116 
J 0
(-561 -3900);
DISPLAY 0.638298 (-561 -3900);
PAINT MONO (-561 -3900);
FORCEPROP 2 LAST CDS_LIB mstr_standard
J 0
(-750 -3900);
PAINT ORANGE (-750 -3900);
DISPLAY INVISIBLE (-750 -3900);
FORCEPROP 2 LAST PATH I42
J 0
(-550 -3850);
DISPLAY 1.021277 (-550 -3850);
PAINT ORANGE (-550 -3850);
DISPLAY INVISIBLE (-550 -3850);
FORCEPROP 1 LAST OFFPAGE TRUE
J 0
(-425 -4025);
DISPLAY 0.872340 (-425 -4025);
PAINT GREEN (-425 -4025);
DISPLAY INVISIBLE (-425 -4025);
FORCEPROP 1 LAST COMMENT_BODY TRUE
J 0
(-795 -3995);
DISPLAY 0.872340 (-795 -3995);
PAINT GREEN (-795 -3995);
DISPLAY INVISIBLE (-795 -3995);
FORCEADD OFFPAGE..2
(-750 -3550);
FORCEPROP 2 LAST $XR0 116 
J 0
(-561 -3550);
DISPLAY 0.638298 (-561 -3550);
PAINT MONO (-561 -3550);
FORCEPROP 2 LAST PATH I43
J 0
(-550 -3500);
DISPLAY 1.021277 (-550 -3500);
PAINT ORANGE (-550 -3500);
DISPLAY INVISIBLE (-550 -3500);
FORCEPROP 2 LAST CDS_LIB mstr_standard
J 0
(-750 -3550);
PAINT ORANGE (-750 -3550);
DISPLAY INVISIBLE (-750 -3550);
FORCEPROP 1 LAST OFFPAGE TRUE
J 0
(-425 -3675);
DISPLAY 0.872340 (-425 -3675);
PAINT GREEN (-425 -3675);
DISPLAY INVISIBLE (-425 -3675);
FORCEPROP 1 LAST COMMENT_BODY TRUE
J 0
(-795 -3645);
DISPLAY 0.872340 (-795 -3645);
PAINT GREEN (-795 -3645);
DISPLAY INVISIBLE (-795 -3645);
FORCEADD GND..1
R 1
(-1400 -3200);
FORCEPROP 3 LASTPIN (-1450 -3200) SIG_NAME GND\g
J 0
(-1440 -3190);
DISPLAY 0.659574 (-1440 -3190);
PAINT MONO (-1440 -3190);
DISPLAY INVISIBLE (-1440 -3190);
FORCEPROP 1 LAST HDL_POWER GND
R 1
J 0
(-1550 -3200);
DISPLAY 0.872340 (-1550 -3200);
PAINT GREEN (-1550 -3200);
DISPLAY INVISIBLE (-1550 -3200);
FORCEPROP 1 LAST BODY_TYPE PLUMBING
R 1
J 0
(-1357 -3245);
DISPLAY 0.340426 (-1357 -3245);
PAINT GREEN (-1357 -3245);
DISPLAY INVISIBLE (-1357 -3245);
FORCEPROP 1 LAST VOLTAGE 0.0V
R 1
J 0
(-1357 -3245);
DISPLAY 0.340426 (-1357 -3245);
PAINT SKYBLUE (-1357 -3245);
DISPLAY INVISIBLE (-1357 -3245);
FORCEPROP 2 LAST CDS_LIB mstr_symbols
R 1
J 0
(-1400 -3200);
PAINT ORANGE (-1400 -3200);
DISPLAY INVISIBLE (-1400 -3200);
FORCEPROP 1 LAST SIZE 1B
R 1
J 0
(-1350 -3125);
DISPLAY 0.872340 (-1350 -3125);
PAINT AQUA (-1350 -3125);
DISPLAY INVISIBLE (-1350 -3125);
FORCEPROP 1 LAST PATH I47
R 1
J 0
(-1400 -3125);
DISPLAY 0.872340 (-1400 -3125);
PAINT AQUA (-1400 -3125);
DISPLAY INVISIBLE (-1400 -3125);
FORCEADD OFFPAGE..4
(-1250 -1300);
FORCEPROP 2 LAST $XR0 158 
J 0
(-1064 -1300);
DISPLAY 0.638298 (-1064 -1300);
PAINT MONO (-1064 -1300);
FORCEPROP 1 LAST COMMENT_BODY TRUE
J 0
(-1275 -1400);
DISPLAY 0.872340 (-1275 -1400);
PAINT GREEN (-1275 -1400);
DISPLAY INVISIBLE (-1275 -1400);
FORCEPROP 1 LAST OFFPAGE TRUE
J 0
(-925 -1425);
DISPLAY 0.872340 (-925 -1425);
PAINT GREEN (-925 -1425);
DISPLAY INVISIBLE (-925 -1425);
FORCEPROP 2 LAST PATH I48
J 0
(-925 -1250);
DISPLAY 1.021277 (-925 -1250);
PAINT ORANGE (-925 -1250);
DISPLAY INVISIBLE (-925 -1250);
FORCEPROP 2 LAST CDS_LIB mstr_standard
J 0
(-1250 -1300);
PAINT MONO (-1250 -1300);
DISPLAY INVISIBLE (-1250 -1300);
FORCEADD OFFPAGE..2
(-1250 -1350);
FORCEPROP 2 LAST $XR0 158 
J 0
(-1061 -1350);
DISPLAY 0.638298 (-1061 -1350);
PAINT MONO (-1061 -1350);
FORCEPROP 1 LAST COMMENT_BODY TRUE
J 0
(-1295 -1445);
DISPLAY 0.872340 (-1295 -1445);
PAINT GREEN (-1295 -1445);
DISPLAY INVISIBLE (-1295 -1445);
FORCEPROP 1 LAST OFFPAGE TRUE
J 0
(-925 -1475);
DISPLAY 0.872340 (-925 -1475);
PAINT GREEN (-925 -1475);
DISPLAY INVISIBLE (-925 -1475);
FORCEPROP 2 LAST CDS_LIB mstr_standard
J 0
(-1250 -1350);
PAINT MONO (-1250 -1350);
DISPLAY INVISIBLE (-1250 -1350);
FORCEPROP 2 LAST PATH I49
J 0
(-925 -1300);
DISPLAY 1.021277 (-925 -1300);
PAINT ORANGE (-925 -1300);
DISPLAY INVISIBLE (-925 -1300);
FORCEADD OFFPAGE..2
(-650 -1800);
FORCEPROP 2 LAST $XR1 158 
J 0
(-281 -1836);
DISPLAY 0.638298 (-281 -1836);
PAINT MONO (-281 -1836);
FORCEPROP 2 LAST $XR0 190 
J 0
(-281 -1800);
DISPLAY 0.638298 (-281 -1800);
PAINT MONO (-281 -1800);
FORCEPROP 1 LAST COMMENT_BODY TRUE
J 0
(-695 -1895);
DISPLAY 0.872340 (-695 -1895);
PAINT GREEN (-695 -1895);
DISPLAY INVISIBLE (-695 -1895);
FORCEPROP 1 LAST OFFPAGE TRUE
J 0
(-325 -1925);
DISPLAY 0.872340 (-325 -1925);
PAINT GREEN (-325 -1925);
DISPLAY INVISIBLE (-325 -1925);
FORCEPROP 2 LAST CDS_LIB mstr_standard
J 0
(-650 -1800);
PAINT MONO (-650 -1800);
DISPLAY INVISIBLE (-650 -1800);
FORCEPROP 2 LAST PATH I51
J 0
(-475 -1725);
DISPLAY 1.021277 (-475 -1725);
PAINT ORANGE (-475 -1725);
DISPLAY INVISIBLE (-475 -1725);
FORCEADD OFFPAGE..4
(-650 -1750);
FORCEPROP 2 LAST $XR1 190 
J 0
(-464 -1714);
DISPLAY 0.638298 (-464 -1714);
PAINT MONO (-464 -1714);
FORCEPROP 2 LAST $XR0 158 
J 0
(-464 -1750);
DISPLAY 0.638298 (-464 -1750);
PAINT MONO (-464 -1750);
FORCEPROP 1 LAST COMMENT_BODY TRUE
J 0
(-675 -1850);
DISPLAY 0.872340 (-675 -1850);
PAINT GREEN (-675 -1850);
DISPLAY INVISIBLE (-675 -1850);
FORCEPROP 1 LAST OFFPAGE TRUE
J 0
(-325 -1875);
DISPLAY 0.872340 (-325 -1875);
PAINT GREEN (-325 -1875);
DISPLAY INVISIBLE (-325 -1875);
FORCEPROP 2 LAST PATH I52
J 0
(-475 -1675);
DISPLAY 1.021277 (-475 -1675);
PAINT ORANGE (-475 -1675);
DISPLAY INVISIBLE (-475 -1675);
FORCEPROP 2 LAST CDS_LIB mstr_standard
J 0
(-650 -1750);
PAINT MONO (-650 -1750);
DISPLAY INVISIBLE (-650 -1750);
FORCEADD OFFPAGE..4
(-1250 -2550);
FORCEPROP 2 LAST $XR2 119 
J 0
(-854 -2550);
DISPLAY 0.638298 (-854 -2550);
PAINT MONO (-854 -2550);
FORCEPROP 2 LAST $XR1 94 
J 0
(-944 -2550);
DISPLAY 0.638298 (-944 -2550);
PAINT MONO (-944 -2550);
FORCEPROP 2 LAST $XR0 215 
J 0
(-1064 -2550);
DISPLAY 0.638298 (-1064 -2550);
PAINT MONO (-1064 -2550);
FORCEPROP 1 LAST COMMENT_BODY TRUE
J 0
(-1275 -2650);
DISPLAY 0.872340 (-1275 -2650);
PAINT GREEN (-1275 -2650);
DISPLAY INVISIBLE (-1275 -2650);
FORCEPROP 1 LAST OFFPAGE TRUE
J 0
(-925 -2675);
DISPLAY 0.872340 (-925 -2675);
PAINT GREEN (-925 -2675);
DISPLAY INVISIBLE (-925 -2675);
FORCEPROP 2 LAST PATH I53
J 0
(-850 -2500);
DISPLAY 1.021277 (-850 -2500);
PAINT ORANGE (-850 -2500);
DISPLAY INVISIBLE (-850 -2500);
FORCEPROP 2 LAST CDS_LIB mstr_standard
J 0
(-1250 -2550);
PAINT MONO (-1250 -2550);
DISPLAY INVISIBLE (-1250 -2550);
FORCEADD OFFPAGE..4
(-1250 -2450);
FORCEPROP 2 LAST $XR1 95 
J 0
(-944 -2450);
DISPLAY 0.638298 (-944 -2450);
PAINT MONO (-944 -2450);
FORCEPROP 2 LAST $XR0 201 
J 0
(-1064 -2450);
DISPLAY 0.638298 (-1064 -2450);
PAINT MONO (-1064 -2450);
FORCEPROP 1 LAST COMMENT_BODY TRUE
J 0
(-1275 -2550);
DISPLAY 0.872340 (-1275 -2550);
PAINT GREEN (-1275 -2550);
DISPLAY INVISIBLE (-1275 -2550);
FORCEPROP 1 LAST OFFPAGE TRUE
J 0
(-925 -2575);
DISPLAY 0.872340 (-925 -2575);
PAINT GREEN (-925 -2575);
DISPLAY INVISIBLE (-925 -2575);
FORCEPROP 2 LAST CDS_LIB mstr_standard
J 0
(-1250 -2450);
PAINT MONO (-1250 -2450);
DISPLAY INVISIBLE (-1250 -2450);
FORCEPROP 2 LAST PATH I54
J 0
(-850 -2400);
DISPLAY 1.021277 (-850 -2400);
PAINT ORANGE (-850 -2400);
DISPLAY INVISIBLE (-850 -2400);
FORCEADD OFFPAGE..4
(-1250 -2400);
FORCEPROP 2 LAST $XR1 95 
J 0
(-944 -2400);
DISPLAY 0.638298 (-944 -2400);
PAINT MONO (-944 -2400);
FORCEPROP 2 LAST $XR0 206 
J 0
(-1064 -2400);
DISPLAY 0.638298 (-1064 -2400);
PAINT MONO (-1064 -2400);
FORCEPROP 1 LAST COMMENT_BODY TRUE
J 0
(-1275 -2500);
DISPLAY 0.872340 (-1275 -2500);
PAINT GREEN (-1275 -2500);
DISPLAY INVISIBLE (-1275 -2500);
FORCEPROP 1 LAST OFFPAGE TRUE
J 0
(-925 -2525);
DISPLAY 0.872340 (-925 -2525);
PAINT GREEN (-925 -2525);
DISPLAY INVISIBLE (-925 -2525);
FORCEPROP 2 LAST CDS_LIB mstr_standard
J 0
(-1250 -2400);
PAINT MONO (-1250 -2400);
DISPLAY INVISIBLE (-1250 -2400);
FORCEPROP 2 LAST PATH I55
J 0
(-850 -2350);
DISPLAY 1.021277 (-850 -2350);
PAINT ORANGE (-850 -2350);
DISPLAY INVISIBLE (-850 -2350);
FORCEADD OFFPAGE..4
(-1250 -2350);
FORCEPROP 2 LAST $XR2 119 
J 0
(-854 -2350);
DISPLAY 0.638298 (-854 -2350);
PAINT MONO (-854 -2350);
FORCEPROP 2 LAST $XR1 94 
J 0
(-944 -2350);
DISPLAY 0.638298 (-944 -2350);
PAINT MONO (-944 -2350);
FORCEPROP 2 LAST $XR0 226 
J 0
(-1064 -2350);
DISPLAY 0.638298 (-1064 -2350);
PAINT MONO (-1064 -2350);
FORCEPROP 1 LAST COMMENT_BODY TRUE
J 0
(-1275 -2450);
DISPLAY 0.872340 (-1275 -2450);
PAINT GREEN (-1275 -2450);
DISPLAY INVISIBLE (-1275 -2450);
FORCEPROP 1 LAST OFFPAGE TRUE
J 0
(-925 -2475);
DISPLAY 0.872340 (-925 -2475);
PAINT GREEN (-925 -2475);
DISPLAY INVISIBLE (-925 -2475);
FORCEPROP 2 LAST CDS_LIB mstr_standard
J 0
(-1250 -2350);
PAINT MONO (-1250 -2350);
DISPLAY INVISIBLE (-1250 -2350);
FORCEPROP 2 LAST PATH I56
J 0
(-850 -2300);
DISPLAY 1.021277 (-850 -2300);
PAINT ORANGE (-850 -2300);
DISPLAY INVISIBLE (-850 -2300);
FORCEADD OFFPAGE..4
(-1250 -2300);
FORCEPROP 2 LAST $XR0 250 
J 0
(-1064 -2300);
DISPLAY 0.638298 (-1064 -2300);
PAINT MONO (-1064 -2300);
FORCEPROP 1 LAST COMMENT_BODY TRUE
J 0
(-1275 -2400);
DISPLAY 0.872340 (-1275 -2400);
PAINT GREEN (-1275 -2400);
DISPLAY INVISIBLE (-1275 -2400);
FORCEPROP 1 LAST OFFPAGE TRUE
J 0
(-925 -2425);
DISPLAY 0.872340 (-925 -2425);
PAINT GREEN (-925 -2425);
DISPLAY INVISIBLE (-925 -2425);
FORCEPROP 2 LAST CDS_LIB mstr_standard
J 0
(-1250 -2300);
PAINT MONO (-1250 -2300);
DISPLAY INVISIBLE (-1250 -2300);
FORCEPROP 2 LAST PATH I57
J 0
(-800 -2250);
DISPLAY 1.021277 (-800 -2250);
PAINT ORANGE (-800 -2250);
DISPLAY INVISIBLE (-800 -2250);
FORCEADD OFFPAGE..4
(-1250 -2200);
FORCEPROP 1 LAST COMMENT_BODY TRUE
J 0
(-1275 -2300);
DISPLAY 0.872340 (-1275 -2300);
PAINT GREEN (-1275 -2300);
DISPLAY INVISIBLE (-1275 -2300);
FORCEPROP 1 LAST OFFPAGE TRUE
J 0
(-925 -2325);
DISPLAY 0.872340 (-925 -2325);
PAINT GREEN (-925 -2325);
DISPLAY INVISIBLE (-925 -2325);
FORCEPROP 2 LAST CDS_LIB mstr_standard
J 0
(-1250 -2200);
PAINT MONO (-1250 -2200);
DISPLAY INVISIBLE (-1250 -2200);
FORCEPROP 2 LAST PATH I58
J 0
(-800 -2150);
DISPLAY 1.021277 (-800 -2150);
PAINT ORANGE (-800 -2150);
DISPLAY INVISIBLE (-800 -2150);
FORCEPROP 2 LAST $XR0 250 
J 0
(-1064 -2200);
DISPLAY 0.638298 (-1064 -2200);
PAINT MONO (-1064 -2200);
DISPLAY INVISIBLE (-1064 -2200);
FORCEADD OFFPAGE..2
(-1250 -2250);
FORCEPROP 2 LAST $XR1 169 
J 0
(-941 -2250);
DISPLAY 0.638298 (-941 -2250);
PAINT MONO (-941 -2250);
FORCEPROP 2 LAST $XR0 118 
J 0
(-1061 -2250);
DISPLAY 0.638298 (-1061 -2250);
PAINT MONO (-1061 -2250);
FORCEPROP 2 LAST CDS_LIB mstr_standard
J 0
(-1250 -2250);
PAINT MONO (-1250 -2250);
DISPLAY INVISIBLE (-1250 -2250);
FORCEPROP 2 LAST PATH I59
J 0
(-925 -2200);
DISPLAY 1.021277 (-925 -2200);
PAINT ORANGE (-925 -2200);
DISPLAY INVISIBLE (-925 -2200);
FORCEPROP 1 LAST OFFPAGE TRUE
J 0
(-925 -2375);
DISPLAY 0.872340 (-925 -2375);
PAINT GREEN (-925 -2375);
DISPLAY INVISIBLE (-925 -2375);
FORCEPROP 1 LAST COMMENT_BODY TRUE
J 0
(-1295 -2345);
DISPLAY 0.872340 (-1295 -2345);
PAINT GREEN (-1295 -2345);
DISPLAY INVISIBLE (-1295 -2345);
FORCEADD OFFPAGE..1
(-6150 -2800);
FORCEPROP 2 LAST $XR2 157 
J 0
(-6672 -2800);
DISPLAY 0.638298 (-6672 -2800);
PAINT MONO (-6672 -2800);
FORCEPROP 2 LAST $XR1 135 
J 0
(-6552 -2800);
DISPLAY 0.638298 (-6552 -2800);
PAINT MONO (-6552 -2800);
FORCEPROP 2 LAST $XR0 118 
J 0
(-6432 -2800);
DISPLAY 0.638298 (-6432 -2800);
PAINT MONO (-6432 -2800);
FORCEPROP 1 LAST COMMENT_BODY TRUE
J 0
(-6025 -2900);
DISPLAY 0.872340 (-6025 -2900);
PAINT GREEN (-6025 -2900);
DISPLAY INVISIBLE (-6025 -2900);
FORCEPROP 1 LAST OFFPAGE TRUE
J 0
(-5825 -2925);
DISPLAY 0.872340 (-5825 -2925);
PAINT GREEN (-5825 -2925);
DISPLAY INVISIBLE (-5825 -2925);
FORCEPROP 2 LAST PATH I6
J 0
(-6400 -2750);
DISPLAY 1.021277 (-6400 -2750);
PAINT ORANGE (-6400 -2750);
DISPLAY INVISIBLE (-6400 -2750);
FORCEPROP 2 LAST CDS_LIB mstr_standard
J 0
(-6150 -2800);
PAINT ORANGE (-6150 -2800);
DISPLAY INVISIBLE (-6150 -2800);
FORCEADD OFFPAGE..1
(-6150 -2850);
FORCEPROP 2 LAST $XR0 145 
J 0
(-6432 -2850);
DISPLAY 0.638298 (-6432 -2850);
PAINT MONO (-6432 -2850);
FORCEPROP 1 LAST COMMENT_BODY TRUE
J 0
(-6025 -2950);
DISPLAY 0.872340 (-6025 -2950);
PAINT GREEN (-6025 -2950);
DISPLAY INVISIBLE (-6025 -2950);
FORCEPROP 1 LAST OFFPAGE TRUE
J 0
(-5825 -2975);
DISPLAY 0.872340 (-5825 -2975);
PAINT GREEN (-5825 -2975);
DISPLAY INVISIBLE (-5825 -2975);
FORCEPROP 2 LAST PATH I7
J 0
(-6400 -2800);
DISPLAY 1.021277 (-6400 -2800);
PAINT ORANGE (-6400 -2800);
DISPLAY INVISIBLE (-6400 -2800);
FORCEPROP 2 LAST CDS_LIB mstr_standard
J 0
(-6150 -2850);
PAINT ORANGE (-6150 -2850);
DISPLAY INVISIBLE (-6150 -2850);
FORCEADD OFFPAGE..4
(-800 -2800);
FORCEPROP 2 LAST $XR1 119 
J 0
(-494 -2800);
DISPLAY 0.638298 (-494 -2800);
PAINT MONO (-494 -2800);
FORCEPROP 2 LAST $XR0 157 
J 0
(-614 -2800);
DISPLAY 0.638298 (-614 -2800);
PAINT MONO (-614 -2800);
FORCEPROP 2 LAST PATH I70
J 0
(-625 -2725);
DISPLAY 1.021277 (-625 -2725);
PAINT ORANGE (-625 -2725);
DISPLAY INVISIBLE (-625 -2725);
FORCEPROP 2 LAST CDS_LIB mstr_standard
J 0
(-800 -2800);
PAINT MONO (-800 -2800);
DISPLAY INVISIBLE (-800 -2800);
FORCEPROP 1 LAST OFFPAGE TRUE
J 0
(-475 -2925);
DISPLAY 0.872340 (-475 -2925);
PAINT GREEN (-475 -2925);
DISPLAY INVISIBLE (-475 -2925);
FORCEPROP 1 LAST COMMENT_BODY TRUE
J 0
(-825 -2900);
DISPLAY 0.872340 (-825 -2900);
PAINT GREEN (-825 -2900);
DISPLAY INVISIBLE (-825 -2900);
FORCEADD OFFPAGE..4
(-800 -2700);
FORCEPROP 2 LAST $XR0 93 
J 0
(-614 -2700);
DISPLAY 0.638298 (-614 -2700);
PAINT MONO (-614 -2700);
FORCEPROP 2 LAST CDS_LIB mstr_standard
J 0
(-800 -2700);
PAINT MONO (-800 -2700);
DISPLAY INVISIBLE (-800 -2700);
FORCEPROP 2 LAST PATH I71
J 0
(-625 -2625);
DISPLAY 1.021277 (-625 -2625);
PAINT ORANGE (-625 -2625);
DISPLAY INVISIBLE (-625 -2625);
FORCEPROP 1 LAST OFFPAGE TRUE
J 0
(-475 -2825);
DISPLAY 0.872340 (-475 -2825);
PAINT GREEN (-475 -2825);
DISPLAY INVISIBLE (-475 -2825);
FORCEPROP 1 LAST COMMENT_BODY TRUE
J 0
(-825 -2800);
DISPLAY 0.872340 (-825 -2800);
PAINT GREEN (-825 -2800);
DISPLAY INVISIBLE (-825 -2800);
FORCEADD OFFPAGE..4
(-800 -2650);
FORCEPROP 2 LAST $XR0 93 
J 0
(-434 -2650);
DISPLAY 0.638298 (-434 -2650);
PAINT MONO (-434 -2650);
FORCEPROP 2 LAST PATH I72
J 0
(-625 -2575);
DISPLAY 1.021277 (-625 -2575);
PAINT ORANGE (-625 -2575);
DISPLAY INVISIBLE (-625 -2575);
FORCEPROP 2 LAST CDS_LIB mstr_standard
J 0
(-800 -2650);
PAINT MONO (-800 -2650);
DISPLAY INVISIBLE (-800 -2650);
FORCEPROP 1 LAST OFFPAGE TRUE
J 0
(-475 -2775);
DISPLAY 0.872340 (-475 -2775);
PAINT GREEN (-475 -2775);
DISPLAY INVISIBLE (-475 -2775);
FORCEPROP 1 LAST COMMENT_BODY TRUE
J 0
(-825 -2750);
DISPLAY 0.872340 (-825 -2750);
PAINT GREEN (-825 -2750);
DISPLAY INVISIBLE (-825 -2750);
FORCEADD OFFPAGE..2
(-800 -2950);
FORCEPROP 2 LAST $XR0 156 
J 0
(-611 -2950);
DISPLAY 0.638298 (-611 -2950);
PAINT MONO (-611 -2950);
FORCEPROP 2 LAST PATH I73
J 0
(-625 -2875);
DISPLAY 1.021277 (-625 -2875);
PAINT ORANGE (-625 -2875);
DISPLAY INVISIBLE (-625 -2875);
FORCEPROP 2 LAST CDS_LIB mstr_standard
J 0
(-800 -2950);
PAINT MONO (-800 -2950);
DISPLAY INVISIBLE (-800 -2950);
FORCEPROP 1 LAST OFFPAGE TRUE
J 0
(-475 -3075);
DISPLAY 0.872340 (-475 -3075);
PAINT GREEN (-475 -3075);
DISPLAY INVISIBLE (-475 -3075);
FORCEPROP 1 LAST COMMENT_BODY TRUE
J 0
(-845 -3045);
DISPLAY 0.872340 (-845 -3045);
PAINT GREEN (-845 -3045);
DISPLAY INVISIBLE (-845 -3045);
FORCEADD OFFPAGE..2
(-800 -2850);
FORCEPROP 2 LAST $XR0 156 
J 0
(-611 -2850);
DISPLAY 0.638298 (-611 -2850);
PAINT MONO (-611 -2850);
FORCEPROP 1 LAST COMMENT_BODY TRUE
J 0
(-845 -2945);
DISPLAY 0.872340 (-845 -2945);
PAINT GREEN (-845 -2945);
DISPLAY INVISIBLE (-845 -2945);
FORCEPROP 1 LAST OFFPAGE TRUE
J 0
(-475 -2975);
DISPLAY 0.872340 (-475 -2975);
PAINT GREEN (-475 -2975);
DISPLAY INVISIBLE (-475 -2975);
FORCEPROP 2 LAST PATH I74
J 0
(-625 -2775);
DISPLAY 1.021277 (-625 -2775);
PAINT ORANGE (-625 -2775);
DISPLAY INVISIBLE (-625 -2775);
FORCEPROP 2 LAST CDS_LIB mstr_standard
J 0
(-800 -2850);
PAINT MONO (-800 -2850);
DISPLAY INVISIBLE (-800 -2850);
FORCEADD OFFPAGE..2
(-800 -2750);
FORCEPROP 2 LAST $XR1 156 
J 0
(-491 -2750);
DISPLAY 0.638298 (-491 -2750);
PAINT MONO (-491 -2750);
FORCEPROP 2 LAST $XR0 120 
J 0
(-611 -2750);
DISPLAY 0.638298 (-611 -2750);
PAINT MONO (-611 -2750);
FORCEPROP 2 LAST PATH I75
J 0
(-625 -2675);
DISPLAY 1.021277 (-625 -2675);
PAINT ORANGE (-625 -2675);
DISPLAY INVISIBLE (-625 -2675);
FORCEPROP 2 LAST CDS_LIB mstr_standard
J 0
(-800 -2750);
PAINT MONO (-800 -2750);
DISPLAY INVISIBLE (-800 -2750);
FORCEPROP 1 LAST OFFPAGE TRUE
J 0
(-475 -2875);
DISPLAY 0.872340 (-475 -2875);
PAINT GREEN (-475 -2875);
DISPLAY INVISIBLE (-475 -2875);
FORCEPROP 1 LAST COMMENT_BODY TRUE
J 0
(-845 -2845);
DISPLAY 0.872340 (-845 -2845);
PAINT GREEN (-845 -2845);
DISPLAY INVISIBLE (-845 -2845);
FORCEADD OSC_C..11
(-5750 -650);
FORCEPROP 1 LAST LOCATION Y9F2
J 0
(-6100 -325);
DISPLAY 0.617021 (-6100 -325);
PAINT AQUA (-6100 -325);
FORCEPROP 1 LAST MATERIAL OSC
J 0
(-6100 -375);
DISPLAY 0.617021 (-6100 -375);
PAINT SKYBLUE (-6100 -375);
FORCEPROP 1 LAST VALUE 24MHZ
J 0
(-6100 -425);
DISPLAY 0.617021 (-6100 -425);
PAINT SKYBLUE (-6100 -425);
FORCEPROP 2 LASTPIN (-6150 -550) $PN 4
J 2
(-6160 -540);
DISPLAY 0.617021 (-6160 -540);
PAINT ORANGE (-6160 -540);
FORCEPROP 2 LASTPIN (-6150 -650) $PN 1
J 2
(-6160 -640);
DISPLAY 0.617021 (-6160 -640);
PAINT ORANGE (-6160 -640);
FORCEPROP 2 LASTPIN (-5350 -750) $PN 2
J 0
(-5340 -740);
DISPLAY 0.617021 (-5340 -740);
PAINT ORANGE (-5340 -740);
FORCEPROP 2 LASTPIN (-5350 -550) $PN 3
J 0
(-5340 -540);
DISPLAY 0.617021 (-5340 -540);
PAINT ORANGE (-5340 -540);
FORCEPROP 1 LAST PART_NUMBER D34520-021
J 0
(-6100 -900);
DISPLAY 0.617021 (-6100 -900);
PAINT BLUE (-6100 -900);
FORCEPROP 0 LAST CDS_SEC 1
J 0
(-6100 -275);
PAINT MONO (-6100 -275);
DISPLAY INVISIBLE (-6100 -275);
FORCEPROP 0 LAST CDS_LOCATION Y9F2
J 0
(-6100 -275);
PAINT MONO (-6100 -275);
DISPLAY INVISIBLE (-6100 -275);
FORCEPROP 1 LAST CDS_LMAN_SYM_OUTLINE -350,200,350,-200
J 0
(-5750 -650);
DISPLAY 0.468085 (-5750 -650);
PAINT GREEN (-5750 -650);
DISPLAY INVISIBLE (-5750 -650);
FORCEPROP 2 LAST CDS_LIB mstr_discrete
J 0
(-5750 -650);
PAINT ORANGE (-5750 -650);
DISPLAY INVISIBLE (-5750 -650);
FORCEPROP 0 LAST ROOM BMC
J 0
(-6100 -225);
DISPLAY 1.021277 (-6100 -225);
PAINT ORANGE (-6100 -225);
DISPLAY INVISIBLE (-6100 -225);
FORCEPROP 2 LAST SEC_TYPE SM4
J 0
(-6100 -275);
DISPLAY 1.021277 (-6100 -275);
PAINT ORANGE (-6100 -275);
DISPLAY INVISIBLE (-6100 -275);
FORCEPROP 0 LAST BOM_COST SM_CONTROLLER
J 0
(-6100 -125);
DISPLAY 1.021277 (-6100 -125);
PAINT ORANGE (-6100 -125);
DISPLAY INVISIBLE (-6100 -125);
FORCEPROP 2 LAST SEC 1
J 0
(-6100 -275);
DISPLAY 0.680851 (-6100 -275);
PAINT MONO (-6100 -275);
DISPLAY INVISIBLE (-6100 -275);
FORCEPROP 1 LAST PACK_TYPE SM4
J 0
(-6100 -275);
PAINT SKYBLUE (-6100 -275);
DISPLAY INVISIBLE (-6100 -275);
FORCEPROP 1 LAST PATH I8
J 0
(-5705 -420);
PAINT GREEN (-5705 -420);
DISPLAY INVISIBLE (-5705 -420);
FORCEADD OFFPAGE..1
(-6150 -1350);
FORCEPROP 2 LAST $XR0 93 
J 0
(-6401 -1350);
DISPLAY 0.638298 (-6401 -1350);
PAINT MONO (-6401 -1350);
FORCEPROP 2 LAST CDS_LIB mstr_standard
J 2
(-6150 -1350);
PAINT ORANGE (-6150 -1350);
DISPLAY INVISIBLE (-6150 -1350);
FORCEPROP 2 LAST ROOM BMC
J 0
(-6400 -1275);
DISPLAY 1.361702 (-6400 -1275);
PAINT ORANGE (-6400 -1275);
DISPLAY INVISIBLE (-6400 -1275);
FORCEPROP 2 LAST BOM_COST SM_CONTROLLER
J 0
(-5700 -1300);
PAINT MONO (-5700 -1300);
DISPLAY INVISIBLE (-5700 -1300);
FORCEPROP 2 LAST PATH I85
J 0
(-6350 -1300);
DISPLAY 1.021277 (-6350 -1300);
PAINT ORANGE (-6350 -1300);
DISPLAY INVISIBLE (-6350 -1300);
FORCEPROP 1 LAST OFFPAGE TRUE
J 0
(-5825 -1475);
DISPLAY 0.872340 (-5825 -1475);
PAINT GREEN (-5825 -1475);
DISPLAY INVISIBLE (-5825 -1475);
FORCEPROP 1 LAST COMMENT_BODY TRUE
J 0
(-6025 -1450);
DISPLAY 0.872340 (-6025 -1450);
PAINT GREEN (-6025 -1450);
DISPLAY INVISIBLE (-6025 -1450);
FORCEADD OFFPAGE..1
(-6150 -1300);
FORCEPROP 2 LAST $XR0 93 
J 0
(-6401 -1300);
DISPLAY 0.638298 (-6401 -1300);
PAINT MONO (-6401 -1300);
FORCEPROP 2 LAST CDS_LIB mstr_standard
J 2
(-6150 -1300);
PAINT ORANGE (-6150 -1300);
DISPLAY INVISIBLE (-6150 -1300);
FORCEPROP 2 LAST ROOM BMC
J 0
(-6400 -1225);
DISPLAY 1.361702 (-6400 -1225);
PAINT ORANGE (-6400 -1225);
DISPLAY INVISIBLE (-6400 -1225);
FORCEPROP 2 LAST BOM_COST SM_CONTROLLER
J 0
(-5700 -1250);
PAINT MONO (-5700 -1250);
DISPLAY INVISIBLE (-5700 -1250);
FORCEPROP 2 LAST PATH I86
J 0
(-6350 -1250);
DISPLAY 1.021277 (-6350 -1250);
PAINT ORANGE (-6350 -1250);
DISPLAY INVISIBLE (-6350 -1250);
FORCEPROP 1 LAST OFFPAGE TRUE
J 0
(-5825 -1425);
DISPLAY 0.872340 (-5825 -1425);
PAINT GREEN (-5825 -1425);
DISPLAY INVISIBLE (-5825 -1425);
FORCEPROP 1 LAST COMMENT_BODY TRUE
J 0
(-6025 -1400);
DISPLAY 0.872340 (-6025 -1400);
PAINT GREEN (-6025 -1400);
DISPLAY INVISIBLE (-6025 -1400);
FORCEADD OFFPAGE..4
(-1250 -2050);
FORCEPROP 2 LAST $XR1 120 
J 0
(-944 -2050);
DISPLAY 0.638298 (-944 -2050);
PAINT MONO (-944 -2050);
FORCEPROP 2 LAST $XR0 200 
J 0
(-1064 -2050);
DISPLAY 0.638298 (-1064 -2050);
PAINT MONO (-1064 -2050);
FORCEPROP 1 LAST COMMENT_BODY TRUE
J 0
(-1275 -2150);
DISPLAY 0.872340 (-1275 -2150);
PAINT GREEN (-1275 -2150);
DISPLAY INVISIBLE (-1275 -2150);
FORCEPROP 1 LAST OFFPAGE TRUE
J 0
(-925 -2175);
DISPLAY 0.872340 (-925 -2175);
PAINT GREEN (-925 -2175);
DISPLAY INVISIBLE (-925 -2175);
FORCEPROP 2 LAST CDS_LIB mstr_standard
J 0
(-1250 -2050);
PAINT ORANGE (-1250 -2050);
DISPLAY INVISIBLE (-1250 -2050);
FORCEPROP 2 LAST PATH I87
J 0
(-925 -2000);
DISPLAY 1.021277 (-925 -2000);
PAINT ORANGE (-925 -2000);
DISPLAY INVISIBLE (-925 -2000);
FORCEADD OFFPAGE..4
(-1250 -2000);
FORCEPROP 2 LAST $XR2 170 
J 0
(-824 -2000);
DISPLAY 0.638298 (-824 -2000);
PAINT MONO (-824 -2000);
FORCEPROP 2 LAST $XR1 120 
J 0
(-944 -2000);
DISPLAY 0.638298 (-944 -2000);
PAINT MONO (-944 -2000);
FORCEPROP 2 LAST $XR0 200 
J 0
(-1064 -2000);
DISPLAY 0.638298 (-1064 -2000);
PAINT MONO (-1064 -2000);
FORCEPROP 1 LAST COMMENT_BODY TRUE
J 0
(-1275 -2100);
DISPLAY 0.872340 (-1275 -2100);
PAINT GREEN (-1275 -2100);
DISPLAY INVISIBLE (-1275 -2100);
FORCEPROP 1 LAST OFFPAGE TRUE
J 0
(-925 -2125);
DISPLAY 0.872340 (-925 -2125);
PAINT GREEN (-925 -2125);
DISPLAY INVISIBLE (-925 -2125);
FORCEPROP 2 LAST CDS_LIB mstr_standard
J 0
(-1250 -2000);
PAINT ORANGE (-1250 -2000);
DISPLAY INVISIBLE (-1250 -2000);
FORCEPROP 2 LAST PATH I88
J 0
(-800 -1950);
DISPLAY 1.021277 (-800 -1950);
PAINT ORANGE (-800 -1950);
DISPLAY INVISIBLE (-800 -1950);
FORCEADD OFFPAGE..4
(-1250 -2100);
FORCEPROP 2 LAST $XR2 170 
J 0
(-824 -2100);
DISPLAY 0.638298 (-824 -2100);
PAINT MONO (-824 -2100);
FORCEPROP 2 LAST $XR1 120 
J 0
(-944 -2100);
DISPLAY 0.638298 (-944 -2100);
PAINT MONO (-944 -2100);
FORCEPROP 2 LAST $XR0 200 
J 0
(-1064 -2100);
DISPLAY 0.638298 (-1064 -2100);
PAINT MONO (-1064 -2100);
FORCEPROP 1 LAST COMMENT_BODY TRUE
J 0
(-1275 -2200);
DISPLAY 0.872340 (-1275 -2200);
PAINT GREEN (-1275 -2200);
DISPLAY INVISIBLE (-1275 -2200);
FORCEPROP 1 LAST OFFPAGE TRUE
J 0
(-925 -2225);
DISPLAY 0.872340 (-925 -2225);
PAINT GREEN (-925 -2225);
DISPLAY INVISIBLE (-925 -2225);
FORCEPROP 2 LAST CDS_LIB mstr_standard
J 0
(-1250 -2100);
PAINT ORANGE (-1250 -2100);
DISPLAY INVISIBLE (-1250 -2100);
FORCEPROP 2 LAST PATH I89
J 0
(-800 -2050);
DISPLAY 1.021277 (-800 -2050);
PAINT ORANGE (-800 -2050);
DISPLAY INVISIBLE (-800 -2050);
FORCEADD OFFPAGE..2
(-3100 -550);
FORCEPROP 2 LAST $XR0 145 
J 0
(-2911 -550);
DISPLAY 0.638298 (-2911 -550);
PAINT MONO (-2911 -550);
FORCEPROP 2 LAST PATH I9
J 0
(-2900 -500);
DISPLAY 1.021277 (-2900 -500);
PAINT ORANGE (-2900 -500);
DISPLAY INVISIBLE (-2900 -500);
FORCEPROP 2 LAST CDS_LIB mstr_standard
J 0
(-3100 -550);
PAINT ORANGE (-3100 -550);
DISPLAY INVISIBLE (-3100 -550);
FORCEPROP 1 LAST OFFPAGE TRUE
J 0
(-2775 -675);
DISPLAY 0.872340 (-2775 -675);
PAINT GREEN (-2775 -675);
DISPLAY INVISIBLE (-2775 -675);
FORCEPROP 1 LAST COMMENT_BODY TRUE
J 0
(-3145 -645);
DISPLAY 0.872340 (-3145 -645);
PAINT GREEN (-3145 -645);
DISPLAY INVISIBLE (-3145 -645);
FORCEADD OFFPAGE..2
(-1250 -1950);
FORCEPROP 2 LAST $XR2 157 
J 0
(-821 -1950);
DISPLAY 0.638298 (-821 -1950);
PAINT MONO (-821 -1950);
FORCEPROP 2 LAST $XR1 136 
J 0
(-941 -1950);
DISPLAY 0.638298 (-941 -1950);
PAINT MONO (-941 -1950);
FORCEPROP 2 LAST $XR0 120 
J 0
(-1061 -1950);
DISPLAY 0.638298 (-1061 -1950);
PAINT MONO (-1061 -1950);
FORCEPROP 1 LAST COMMENT_BODY TRUE
J 0
(-1295 -2045);
DISPLAY 0.872340 (-1295 -2045);
PAINT GREEN (-1295 -2045);
DISPLAY INVISIBLE (-1295 -2045);
FORCEPROP 1 LAST OFFPAGE TRUE
J 0
(-925 -2075);
DISPLAY 0.872340 (-925 -2075);
PAINT GREEN (-925 -2075);
DISPLAY INVISIBLE (-925 -2075);
FORCEPROP 2 LAST CDS_LIB mstr_standard
J 0
(-1250 -1950);
PAINT ORANGE (-1250 -1950);
DISPLAY INVISIBLE (-1250 -1950);
FORCEPROP 2 LAST PATH I90
J 0
(-800 -1900);
DISPLAY 1.021277 (-800 -1900);
PAINT ORANGE (-800 -1900);
DISPLAY INVISIBLE (-800 -1900);
FORCEADD OFFPAGE..4
(-650 -1900);
FORCEPROP 2 LAST $XR1 120 
J 0
(-464 -1936);
DISPLAY 0.638298 (-464 -1936);
PAINT MONO (-464 -1936);
FORCEPROP 2 LAST $XR0 191 
J 0
(-464 -1900);
DISPLAY 0.638298 (-464 -1900);
PAINT MONO (-464 -1900);
FORCEPROP 1 LAST COMMENT_BODY TRUE
J 0
(-675 -2000);
DISPLAY 0.872340 (-675 -2000);
PAINT GREEN (-675 -2000);
DISPLAY INVISIBLE (-675 -2000);
FORCEPROP 1 LAST OFFPAGE TRUE
J 0
(-325 -2025);
DISPLAY 0.872340 (-325 -2025);
PAINT GREEN (-325 -2025);
DISPLAY INVISIBLE (-325 -2025);
FORCEPROP 2 LAST CDS_LIB mstr_standard
J 0
(-650 -1900);
PAINT ORANGE (-650 -1900);
DISPLAY INVISIBLE (-650 -1900);
FORCEPROP 2 LAST PATH I91
J 0
(-325 -1850);
DISPLAY 1.021277 (-325 -1850);
PAINT ORANGE (-325 -1850);
DISPLAY INVISIBLE (-325 -1850);
FORCEADD OFFPAGE..2
(-650 -1850);
FORCEPROP 2 LAST $XR1 170 
J 0
(-461 -1814);
DISPLAY 0.638298 (-461 -1814);
PAINT MONO (-461 -1814);
FORCEPROP 2 LAST $XR0 119 
J 0
(-461 -1850);
DISPLAY 0.638298 (-461 -1850);
PAINT MONO (-461 -1850);
FORCEPROP 1 LAST COMMENT_BODY TRUE
J 0
(-695 -1945);
DISPLAY 0.872340 (-695 -1945);
PAINT GREEN (-695 -1945);
DISPLAY INVISIBLE (-695 -1945);
FORCEPROP 1 LAST OFFPAGE TRUE
J 0
(-325 -1975);
DISPLAY 0.872340 (-325 -1975);
PAINT GREEN (-325 -1975);
DISPLAY INVISIBLE (-325 -1975);
FORCEPROP 2 LAST CDS_LIB mstr_standard
J 0
(-650 -1850);
PAINT ORANGE (-650 -1850);
DISPLAY INVISIBLE (-650 -1850);
FORCEPROP 2 LAST PATH I92
J 0
(-325 -1800);
DISPLAY 1.021277 (-325 -1800);
PAINT ORANGE (-325 -1800);
DISPLAY INVISIBLE (-325 -1800);
FORCEADD OFFPAGE..4
(-1250 -1600);
FORCEPROP 2 LAST $XR2 120 
J 0
(-854 -1600);
DISPLAY 0.638298 (-854 -1600);
PAINT MONO (-854 -1600);
FORCEPROP 2 LAST $XR1 133 
J 0
(-974 -1600);
DISPLAY 0.638298 (-974 -1600);
PAINT MONO (-974 -1600);
FORCEPROP 2 LAST $XR0 56 
J 0
(-1064 -1600);
DISPLAY 0.638298 (-1064 -1600);
PAINT MONO (-1064 -1600);
FORCEPROP 1 LAST COMMENT_BODY TRUE
J 0
(-1275 -1700);
DISPLAY 0.872340 (-1275 -1700);
PAINT GREEN (-1275 -1700);
DISPLAY INVISIBLE (-1275 -1700);
FORCEPROP 1 LAST OFFPAGE TRUE
J 0
(-925 -1725);
DISPLAY 0.872340 (-925 -1725);
PAINT GREEN (-925 -1725);
DISPLAY INVISIBLE (-925 -1725);
FORCEPROP 2 LAST PATH I93
J 0
(-850 -1550);
DISPLAY 1.021277 (-850 -1550);
PAINT ORANGE (-850 -1550);
DISPLAY INVISIBLE (-850 -1550);
FORCEPROP 2 LAST CDS_LIB mstr_standard
J 0
(-1250 -1600);
PAINT ORANGE (-1250 -1600);
DISPLAY INVISIBLE (-1250 -1600);
FORCEADD OFFPAGE..4
(-1250 -1650);
FORCEPROP 2 LAST $XR3 120 
J 0
(-734 -1650);
DISPLAY 0.638298 (-734 -1650);
PAINT MONO (-734 -1650);
FORCEPROP 2 LAST $XR2 118 
J 0
(-854 -1650);
DISPLAY 0.638298 (-854 -1650);
PAINT MONO (-854 -1650);
FORCEPROP 2 LAST $XR1 133 
J 0
(-974 -1650);
DISPLAY 0.638298 (-974 -1650);
PAINT MONO (-974 -1650);
FORCEPROP 2 LAST $XR0 22 
J 0
(-1064 -1650);
DISPLAY 0.638298 (-1064 -1650);
PAINT MONO (-1064 -1650);
FORCEPROP 1 LAST COMMENT_BODY TRUE
J 0
(-1275 -1750);
DISPLAY 0.872340 (-1275 -1750);
PAINT GREEN (-1275 -1750);
DISPLAY INVISIBLE (-1275 -1750);
FORCEPROP 1 LAST OFFPAGE TRUE
J 0
(-925 -1775);
DISPLAY 0.872340 (-925 -1775);
PAINT GREEN (-925 -1775);
DISPLAY INVISIBLE (-925 -1775);
FORCEPROP 2 LAST CDS_LIB mstr_standard
J 0
(-1250 -1650);
PAINT ORANGE (-1250 -1650);
DISPLAY INVISIBLE (-1250 -1650);
FORCEPROP 2 LAST PATH I94
J 0
(-725 -1600);
DISPLAY 1.021277 (-725 -1600);
PAINT ORANGE (-725 -1600);
DISPLAY INVISIBLE (-725 -1600);
FORCEADD OFFPAGE..2
(-1250 -1500);
FORCEPROP 2 LAST $XR2 200 
J 0
(-821 -1500);
DISPLAY 0.638298 (-821 -1500);
PAINT MONO (-821 -1500);
FORCEPROP 2 LAST $XR1 126 
J 0
(-941 -1500);
DISPLAY 0.638298 (-941 -1500);
PAINT MONO (-941 -1500);
FORCEPROP 2 LAST $XR0 120 
J 0
(-1061 -1500);
DISPLAY 0.638298 (-1061 -1500);
PAINT MONO (-1061 -1500);
FORCEPROP 1 LAST COMMENT_BODY TRUE
J 0
(-1295 -1595);
DISPLAY 0.872340 (-1295 -1595);
PAINT GREEN (-1295 -1595);
DISPLAY INVISIBLE (-1295 -1595);
FORCEPROP 1 LAST OFFPAGE TRUE
J 0
(-925 -1625);
DISPLAY 0.872340 (-925 -1625);
PAINT GREEN (-925 -1625);
DISPLAY INVISIBLE (-925 -1625);
FORCEPROP 2 LAST CDS_LIB mstr_standard
J 0
(-1250 -1500);
PAINT ORANGE (-1250 -1500);
DISPLAY INVISIBLE (-1250 -1500);
FORCEPROP 2 LAST PATH I95
J 0
(-800 -1450);
DISPLAY 1.021277 (-800 -1450);
PAINT ORANGE (-800 -1450);
DISPLAY INVISIBLE (-800 -1450);
FORCEADD OFFPAGE..2
(-1250 -1550);
FORCEPROP 2 LAST $XR2 182 
J 0
(-821 -1550);
DISPLAY 0.638298 (-821 -1550);
PAINT MONO (-821 -1550);
FORCEPROP 2 LAST $XR1 133 
J 0
(-941 -1550);
DISPLAY 0.638298 (-941 -1550);
PAINT MONO (-941 -1550);
FORCEPROP 2 LAST $XR0 120 
J 0
(-1061 -1550);
DISPLAY 0.638298 (-1061 -1550);
PAINT MONO (-1061 -1550);
FORCEPROP 1 LAST COMMENT_BODY TRUE
J 0
(-1295 -1645);
DISPLAY 0.872340 (-1295 -1645);
PAINT GREEN (-1295 -1645);
DISPLAY INVISIBLE (-1295 -1645);
FORCEPROP 1 LAST OFFPAGE TRUE
J 0
(-925 -1675);
DISPLAY 0.872340 (-925 -1675);
PAINT GREEN (-925 -1675);
DISPLAY INVISIBLE (-925 -1675);
FORCEPROP 2 LAST PATH I96
J 0
(-800 -1500);
DISPLAY 1.021277 (-800 -1500);
PAINT ORANGE (-800 -1500);
DISPLAY INVISIBLE (-800 -1500);
FORCEPROP 2 LAST CDS_LIB mstr_standard
J 0
(-1250 -1550);
PAINT ORANGE (-1250 -1550);
DISPLAY INVISIBLE (-1250 -1550);
FORCEADD OFFPAGE..6
(-6150 -2700);
FORCEPROP 2 LAST $XR0 145 
J 0
(-6430 -2700);
DISPLAY 0.638298 (-6430 -2700);
PAINT MONO (-6430 -2700);
FORCEPROP 1 LAST COMMENT_BODY TRUE
J 0
(-6050 -2775);
DISPLAY 0.872340 (-6050 -2775);
PAINT GREEN (-6050 -2775);
DISPLAY INVISIBLE (-6050 -2775);
FORCEPROP 1 LAST OFFPAGE TRUE
J 0
(-5825 -2825);
DISPLAY 0.872340 (-5825 -2825);
PAINT GREEN (-5825 -2825);
DISPLAY INVISIBLE (-5825 -2825);
FORCEPROP 2 LAST PATH I99
J 0
(-6425 -2650);
DISPLAY 1.021277 (-6425 -2650);
PAINT ORANGE (-6425 -2650);
DISPLAY INVISIBLE (-6425 -2650);
FORCEPROP 2 LAST CDS_LIB mstr_standard
J 0
(-6150 -2700);
PAINT ORANGE (-6150 -2700);
DISPLAY INVISIBLE (-6150 -2700);
FORCEADD INTEL_CORP_BPAGE..1
(-300 -5025);
FORCEPROP 1 LAST CDS_CON_LAST_MODIFIED Fri Jun 16 17:48:54 2017
J 0
(-1725 -4700);
DISPLAY 1.361702 (-1725 -4700);
PAINT GREEN (-1725 -4700);
DISPLAY INVISIBLE (-1725 -4700);
FORCEPROP 2 LAST CUSTOM_TXT_CDS <XR_PAGE_TITLE>
J 0
(-8190 225);
DISPLAY 0.638298 (-8190 225);
PAINT PINK (-8190 225);
DISPLAY INVISIBLE (-8190 225);
FORCEPROP 2 LAST CUSTOM_TXT_CDS <CON_LAST_MODIFIED>
J 0
(-4300 -4925);
PAINT ORANGE (-4300 -4925);
FORCEPROP 2 LAST CUSTOM_TXT_CDS <CURRENT_DESIGN_SHEET> OF <TOTAL_DESIGN_SHEETS>
J 0
(-800 -5000);
PAINT ORANGE (-800 -5000);
FORCEPROP 1 LAST SCH_TITLE BMC (3 OF 7)
J 0
(-8250 -4975);
DISPLAY 1.212766 (-8250 -4975);
PAINT ORANGE (-8250 -4975);
FORCEPROP 2 LAST CDS_LIB mstr_symbols
J 0
(-300 -5025);
DISPLAY 1.361702 (-300 -5025);
PAINT ORANGE (-300 -5025);
DISPLAY INVISIBLE (-300 -5025);
FORCEPROP 2 LAST PAGE_BORDER TRUE
J 0
(-8190 225);
DISPLAY 0.851064 (-8190 225);
PAINT PINK (-8190 225);
DISPLAY INVISIBLE (-8190 225);
FORCEPROP 1 LAST COMMENT_BODY TRUE
J 0
(-288 -5013);
DISPLAY 0.617021 (-288 -5013);
PAINT GREEN (-288 -5013);
DISPLAY INVISIBLE (-288 -5013);
FORCEPROP 2 LAST CDS_XR_PAGE_TITLE CR-145 : @BASEBOARD_FAB2_LIB.BASEBOARD_FAB2(SCH_1):PAGE145
J 0
(-8190 225);
DISPLAY 0.638298 (-8190 225);
PAINT PINK (-8190 225);
DISPLAY INVISIBLE (-8190 225);
FORCEADD DNS..2
(-7045 -4205);
PAINT RED (-7045 -4205);
FORCEPROP 1 LAST COMMENT_BODY TRUE
R 1
J 0
(-6970 -4430);
DISPLAY 0.872340 (-6970 -4430);
PAINT GREEN (-6970 -4430);
DISPLAY INVISIBLE (-6970 -4430);
FORCEPROP 2 LAST CDS_LIB mstr_misc
J 0
(-7045 -4205);
PAINT MONO (-7045 -4205);
DISPLAY INVISIBLE (-7045 -4205);
FORCEADD CAD_NOTE..1
(-7975 -725);
FORCEPROP 0 LAST L2 VDD PIN
J 0
(-8125 -925);
DISPLAY 1.021277 (-8125 -925);
PAINT ORANGE (-8125 -925);
FORCEPROP 0 LAST L1 PLACE 0.1UF CAP CLOSE TO OSC
J 0
(-8125 -850);
DISPLAY 1.021277 (-8125 -850);
PAINT ORANGE (-8125 -850);
FORCEPROP 1 LAST COMMENT_BODY TRUE
J 0
(-7950 -625);
DISPLAY 0.978723 (-7950 -625);
PAINT ORANGE (-7950 -625);
DISPLAY INVISIBLE (-7950 -625);
FORCEPROP 2 LAST CDS_LIB mstr_symbols
J 0
(-7975 -725);
PAINT ORANGE (-7975 -725);
DISPLAY INVISIBLE (-7975 -725);
FORCEADD DNS..2
(-4445 -255);
PAINT RED (-4445 -255);
FORCEPROP 1 LAST COMMENT_BODY TRUE
R 1
J 0
(-4370 -480);
DISPLAY 0.872340 (-4370 -480);
PAINT GREEN (-4370 -480);
DISPLAY INVISIBLE (-4370 -480);
FORCEPROP 2 LAST CDS_LIB mstr_misc
J 0
(-4445 -255);
PAINT ORANGE (-4445 -255);
DISPLAY INVISIBLE (-4445 -255);
FORCEADD DNS..2
(-7295 -3980);
PAINT RED (-7295 -3980);
FORCEPROP 2 LAST CDS_LIB mstr_misc
J 0
(-7295 -3980);
PAINT MONO (-7295 -3980);
DISPLAY INVISIBLE (-7295 -3980);
FORCEPROP 1 LAST COMMENT_BODY TRUE
R 1
J 0
(-7220 -4205);
DISPLAY 0.872340 (-7220 -4205);
PAINT GREEN (-7220 -4205);
DISPLAY INVISIBLE (-7220 -4205);
FORCEADD CAD_NOTE..1
(-3625 -175);
FORCEPROP 0 LAST L1 USE SHARED PADS
J 0
(-3775 -300);
DISPLAY 0.808511 (-3775 -300);
PAINT ORANGE (-3775 -300);
FORCEPROP 1 LAST COMMENT_BODY TRUE
J 0
(-3600 -75);
DISPLAY 0.978723 (-3600 -75);
PAINT ORANGE (-3600 -75);
DISPLAY INVISIBLE (-3600 -75);
FORCEPROP 2 LAST CDS_LIB mstr_symbols
J 0
(-3625 -175);
PAINT ORANGE (-3625 -175);
DISPLAY INVISIBLE (-3625 -175);
FORCEADD DNS..2
(-7645 -3430);
PAINT RED (-7645 -3430);
FORCEPROP 1 LAST COMMENT_BODY TRUE
R 1
J 0
(-7570 -3655);
DISPLAY 0.872340 (-7570 -3655);
PAINT GREEN (-7570 -3655);
DISPLAY INVISIBLE (-7570 -3655);
FORCEPROP 2 LAST CDS_LIB mstr_misc
J 0
(-7645 -3430);
PAINT ORANGE (-7645 -3430);
DISPLAY INVISIBLE (-7645 -3430);
WIRE 16 -1 (-7050 -4300)(-7050 -4350);
WIRE 16 -1 (-5275 -825)(-5275 -750);
WIRE 16 -1 (-5275 -750)(-5350 -750);
WIRE 16 -1 (-7500 -300)(-7500 -250);
WIRE 16 -1 (-7000 -300)(-7500 -300);
WIRE 16 -1 (-7500 -350)(-7500 -300);
WIRE 16 -1 (-6550 -300)(-7000 -300);
WIRE 16 -1 (-7000 -300)(-7000 -375);
WIRE 16 -1 (-6550 -550)(-6550 -300);
WIRE 16 -1 (-6150 -550)(-6550 -550);
WIRE 16 -1 (-7500 -550)(-7500 -625);
WIRE 16 -1 (-7650 -3525)(-7650 -3575);
WIRE 16 -1 (-5200 -4250)(-5200 -4300);
WIRE 16 -1 (-5450 -4250)(-5450 -4300);
WIRE 16 -1 (-5700 -4250)(-5700 -4300);
WIRE 16 -1 (-5950 -4250)(-5950 -4300);
WIRE 16 -1 (-6200 -4250)(-6200 -4300);
WIRE 16 -1 (-1450 -3200)(-1500 -3200);
WIRE 16 -1 (-2500 -1950)(-1300 -1950);
FORCEPROP 0 LAST SIG_NAME FM_BIOS_TOP_SWAP
J 0
(-2300 -1940);
DISPLAY 0.680851 (-2300 -1940);
PAINT ORANGE (-2300 -1940);
WIRE 16 -1 (-7700 -2950)(-6550 -2950);
FORCEPROP 0 LAST CDS_PHYS_NET_NAME IRQ_FORCE_NM_THROTTLE_N
J 0
(-7700 -2911);
PAINT MONO (-7700 -2911);
DISPLAY INVISIBLE (-7700 -2911);
FORCEPROP 2 LAST SIG_NAME IRQ_FORCE_NM_THROTTLE_N
J 0
(-7660 -2940);
DISPLAY 0.638298 (-7660 -2940);
PAINT ORANGE (-7660 -2940);
WIRE 16 -1 (-6100 -2800)(-5100 -2800);
FORCEPROP 2 LAST SIG_NAME RST_BMC_SRST_N
J 0
(-6035 -2790);
DISPLAY 0.638298 (-6035 -2790);
PAINT ORANGE (-6035 -2790);
WIRE 16 -1 (-6100 -2850)(-5100 -2850);
FORCEPROP 2 LAST SIG_NAME CLK_24M_25M_BMC_CLKIN
J 0
(-6035 -2840);
DISPLAY 0.638298 (-6035 -2840);
PAINT ORANGE (-6035 -2840);
WIRE 16 -1 (-5100 -3000)(-6100 -3000);
FORCEPROP 2 LAST SIG_NAME TP_BMC_GPIOA2
J 0
(-6035 -2990);
DISPLAY 0.638298 (-6035 -2990);
PAINT ORANGE (-6035 -2990);
FORCEPROP 2 LASTPROP $XRERR UNIQUE?
J 0
(-6340 -3000);
DISPLAY 0.638298 (-6340 -3000);
PAINT MONO (-6340 -3000);
DISPLAY INVISIBLE (-6340 -3000);
WIRE 16 -1 (-2500 -3350)(-2400 -3350);
WIRE 16 -1 (-2400 -3350)(-2400 -3900);
WIRE 16 -1 (-1750 -3900)(-2400 -3900);
FORCEPROP 2 LAST SIG_NAME P2E_SSB_BMC_RX_DN
J 0
(-2310 -3890);
DISPLAY 0.680851 (-2310 -3890);
PAINT ORANGE (-2310 -3890);
FORCEPROP 2 LASTPROP $XRERR UNIQUE?
J 0
(-2550 -3890);
DISPLAY 0.638298 (-2550 -3890);
PAINT MONO (-2550 -3890);
DISPLAY INVISIBLE (-2550 -3890);
WIRE 2 -1 (-7625 -2800)(-7625 -2750);
WIRE 2 -1 (-6700 -2800)(-7625 -2800);
WIRE 16 -1 (-1400 -2900)(-850 -2900);
FORCEPROP 0 LAST SIG_NAME FM_PWR_BTN_N
J 0
(-1350 -2890);
DISPLAY 0.680851 (-1350 -2890);
PAINT ORANGE (-1350 -2890);
WIRE 16 -1 (-1400 -3000)(-850 -3000);
FORCEPROP 0 LAST SIG_NAME RST_SYSTEM_BTN_N
J 0
(-1350 -2990);
DISPLAY 0.680851 (-1350 -2990);
PAINT ORANGE (-1350 -2990);
WIRE 16 -1 (-1550 -3550)(-800 -3550);
FORCEPROP 2 LAST SIG_NAME P2E_SSB_BMC_RX_C_DP
J 0
(-1435 -3540);
DISPLAY 0.680851 (-1435 -3540);
PAINT ORANGE (-1435 -3540);
WIRE 16 -1 (-1550 -3900)(-800 -3900);
FORCEPROP 2 LAST SIG_NAME P2E_SSB_BMC_RX_C_DN
J 0
(-1435 -3890);
DISPLAY 0.680851 (-1435 -3890);
PAINT ORANGE (-1435 -3890);
WIRE 16 -1 (-6100 -3350)(-5100 -3350);
FORCEPROP 2 LAST SIG_NAME UART_BMC_RXD5
J 0
(-6035 -3340);
DISPLAY 0.617021 (-6035 -3340);
PAINT ORANGE (-6035 -3340);
WIRE 16 -1 (-5200 -4050)(-5200 -3450);
WIRE 16 -1 (-5200 -3450)(-5100 -3450);
WIRE 16 -1 (-5850 -3450)(-5200 -3450);
FORCEPROP 2 LAST SIG_NAME RST_PLTRST_BUF_N_R
J 0
(-5785 -3440);
DISPLAY 0.617021 (-5785 -3440);
PAINT ORANGE (-5785 -3440);
FORCEPROP 2 LASTPROP $XRERR UNIQUE?
J 0
(-6025 -3440);
DISPLAY 0.638298 (-6025 -3440);
PAINT MONO (-6025 -3440);
DISPLAY INVISIBLE (-6025 -3440);
WIRE 16 -1 (-5700 -3600)(-6600 -3600);
FORCEPROP 2 LAST SIG_NAME CLK_100M_BMC_PE_R_DN
J 0
(-6610 -3590);
DISPLAY 0.617021 (-6610 -3590);
PAINT ORANGE (-6610 -3590);
WIRE 16 -1 (-5700 -3600)(-5700 -4050);
WIRE 16 -1 (-5100 -3600)(-5700 -3600);
WIRE 16 -1 (-5950 -3700)(-5950 -4050);
WIRE 16 -1 (-5950 -3700)(-5100 -3700);
WIRE 16 -1 (-6600 -3700)(-5950 -3700);
FORCEPROP 2 LAST SIG_NAME P2E_SSB_BMC_TX_C_DP
J 0
(-6610 -3690);
DISPLAY 0.617021 (-6610 -3690);
PAINT ORANGE (-6610 -3690);
WIRE 16 -1 (-6200 -3750)(-6600 -3750);
FORCEPROP 2 LAST SIG_NAME P2E_SSB_BMC_TX_C_DN
J 0
(-6610 -3740);
DISPLAY 0.617021 (-6610 -3740);
PAINT ORANGE (-6610 -3740);
WIRE 16 -1 (-6200 -4050)(-6200 -3750);
WIRE 16 -1 (-5100 -3750)(-6200 -3750);
WIRE 16 -1 (-5100 -2000)(-6100 -2000);
FORCEPROP 0 LAST SIG_NAME SMB_PEHPCPU1_STBY_LVC3_SDA
J 0
(-6035 -1990);
DISPLAY 0.617021 (-6035 -1990);
PAINT ORANGE (-6035 -1990);
WIRE 16 -1 (-6100 -1750)(-5100 -1750);
FORCEPROP 0 LAST CDS_PHYS_NET_NAME FM_BIOS_MRC_DEBUG_MSG_DIS_N
J 0
(-5175 -1711);
PAINT MONO (-5175 -1711);
DISPLAY INVISIBLE (-5175 -1711);
FORCEPROP 2 LAST SIG_NAME FM_BIOS_MRC_DEBUG_MSG_DIS_N
J 0
(-6035 -1740);
DISPLAY 0.638298 (-6035 -1740);
PAINT ORANGE (-6035 -1740);
FORCEPROP 0 LAST PHYS_NET_NAME FM_BIOS_MRC_DEBUG_MSG_DIS_N
J 0
(-5175 -1664);
PAINT MONO (-5175 -1664);
DISPLAY INVISIBLE (-5175 -1664);
WIRE 16 -1 (-2500 -1400)(-1300 -1400);
FORCEPROP 0 LAST SIG_NAME FM_CPU1_THERMTRIP_LATCH_LVT3_N
J 0
(-2300 -1390);
DISPLAY 0.680851 (-2300 -1390);
PAINT ORANGE (-2300 -1390);
WIRE 16 -1 (-2500 -1500)(-1300 -1500);
FORCEPROP 0 LAST CDS_PHYS_NET_NAME FM_OC_DETECT_EN_N
J 0
(-1300 -1461);
PAINT MONO (-1300 -1461);
DISPLAY INVISIBLE (-1300 -1461);
FORCEPROP 0 LAST PHYS_NET_NAME FM_OC_DETECT_EN_N
J 0
(-1300 -1414);
PAINT MONO (-1300 -1414);
DISPLAY INVISIBLE (-1300 -1414);
FORCEPROP 0 LAST SIG_NAME FM_OC_DETECT_EN_N
J 0
(-2300 -1490);
DISPLAY 0.680851 (-2300 -1490);
PAINT ORANGE (-2300 -1490);
WIRE 16 -1 (-2500 -1550)(-1300 -1550);
FORCEPROP 0 LAST CDS_PHYS_NET_NAME IRQ_BOARD_BMC_ALERT_N
J 0
(-1300 -1511);
PAINT MONO (-1300 -1511);
DISPLAY INVISIBLE (-1300 -1511);
FORCEPROP 0 LAST PHYS_NET_NAME IRQ_BOARD_BMC_ALERT_N
J 0
(-1300 -1464);
PAINT MONO (-1300 -1464);
DISPLAY INVISIBLE (-1300 -1464);
FORCEPROP 0 LAST SIG_NAME IRQ_BOARD_BMC_ALERT_N
J 0
(-2300 -1540);
DISPLAY 0.680851 (-2300 -1540);
PAINT ORANGE (-2300 -1540);
WIRE 16 -1 (-2500 -1600)(-1300 -1600);
FORCEPROP 0 LAST CDS_PHYS_NET_NAME FM_CPU1_RC_ERROR_N
J 0
(-1300 -1561);
PAINT MONO (-1300 -1561);
DISPLAY INVISIBLE (-1300 -1561);
FORCEPROP 0 LAST PHYS_NET_NAME FM_CPU1_RC_ERROR_N
J 0
(-1300 -1514);
PAINT MONO (-1300 -1514);
DISPLAY INVISIBLE (-1300 -1514);
FORCEPROP 0 LAST SIG_NAME FM_CPU1_RC_ERROR_N
J 0
(-2300 -1590);
DISPLAY 0.680851 (-2300 -1590);
PAINT ORANGE (-2300 -1590);
WIRE 16 -1 (-2500 -1650)(-1300 -1650);
FORCEPROP 0 LAST SIG_NAME FM_CPU0_RC_ERROR_N
J 0
(-2300 -1640);
DISPLAY 0.680851 (-2300 -1640);
PAINT ORANGE (-2300 -1640);
WIRE 16 -1 (-2500 -1750)(-700 -1750);
FORCEPROP 0 LAST SIG_NAME SP1_BMC_HOST_UART_RX
J 0
(-1350 -1740);
DISPLAY 0.680851 (-1350 -1740);
PAINT ORANGE (-1350 -1740);
WIRE 16 -1 (-2500 -1800)(-700 -1800);
FORCEPROP 0 LAST SIG_NAME SP1_BMC_HOST_UART_TX
J 0
(-1350 -1790);
DISPLAY 0.680851 (-1350 -1790);
PAINT ORANGE (-1350 -1790);
WIRE 16 -1 (-2500 -1850)(-1600 -1850);
FORCEPROP 0 LAST SIG_NAME FM_PMBUS_ALERT_BUF_EN_R3_N
J 0
(-2350 -1840);
DISPLAY 0.680851 (-2350 -1840);
PAINT ORANGE (-2350 -1840);
FORCEPROP 2 LASTPROP $XRERR UNIQUE?
J 0
(-2590 -1840);
DISPLAY 0.638298 (-2590 -1840);
PAINT MONO (-2590 -1840);
DISPLAY INVISIBLE (-2590 -1840);
WIRE 16 -1 (-2500 -1900)(-700 -1900);
FORCEPROP 0 LAST SIG_NAME FM_MEM_THERM_EVENT_PCH_N
J 0
(-1350 -1890);
DISPLAY 0.680851 (-1350 -1890);
PAINT ORANGE (-1350 -1890);
WIRE 16 -1 (-2500 -2050)(-1300 -2050);
FORCEPROP 0 LAST SIG_NAME IRQ_OC_DETECT_N
J 0
(-2300 -2040);
DISPLAY 0.680851 (-2300 -2040);
PAINT ORANGE (-2300 -2040);
WIRE 16 -1 (-2500 -2100)(-1300 -2100);
FORCEPROP 0 LAST SIG_NAME IRQ_UV_DETECT_N
J 0
(-2300 -2090);
DISPLAY 0.680851 (-2300 -2090);
PAINT ORANGE (-2300 -2090);
WIRE 16 -1 (-2500 -2400)(-1300 -2400);
FORCEPROP 2 LAST SIG_NAME IRQ_PVCCIN_CPU1_VRHOT_LVC3_N
J 0
(-2300 -2390);
DISPLAY 0.680851 (-2300 -2390);
PAINT ORANGE (-2300 -2390);
WIRE 16 -1 (-2500 -2500)(-1300 -2500);
FORCEPROP 0 LAST SIG_NAME SPI_BMC_BT_WP0_N
J 0
(-2300 -2490);
DISPLAY 0.680851 (-2300 -2490);
PAINT ORANGE (-2300 -2490);
WIRE 16 -1 (-2500 -2550)(-1300 -2550);
FORCEPROP 0 LAST SIG_NAME IRQ_PVDDQ_ABC_VRHOT_LVT3_N
J 0
(-2300 -2540);
DISPLAY 0.680851 (-2300 -2540);
PAINT ORANGE (-2300 -2540);
WIRE 16 -1 (-2500 -2200)(-1300 -2200);
FORCEPROP 0 LAST SIG_NAME FM_OCP_MEZZC_PRES_LVT3_BMC
J 0
(-2300 -2190);
DISPLAY 0.680851 (-2300 -2190);
PAINT ORANGE (-2300 -2190);
WIRE 16 -1 (-2500 -2300)(-1300 -2300);
FORCEPROP 0 LAST SIG_NAME FM_OCP_MEZZB_PRES_LVT3_BMC
J 0
(-2300 -2290);
DISPLAY 0.680851 (-2300 -2290);
PAINT ORANGE (-2300 -2290);
WIRE 16 -1 (-1400 -1850)(-700 -1850);
FORCEPROP 0 LAST SIG_NAME FM_PMBUS_ALERT_BUF_EN_N
J 0
(-1350 -1840);
DISPLAY 0.680851 (-1350 -1840);
PAINT ORANGE (-1350 -1840);
WIRE 16 -1 (-2500 -2000)(-1300 -2000);
FORCEPROP 0 LAST SIG_NAME FM_HSC_TIMER_EXP_N
J 0
(-2300 -1990);
DISPLAY 0.680851 (-2300 -1990);
PAINT ORANGE (-2300 -1990);
WIRE 16 -1 (-2500 -2250)(-1300 -2250);
FORCEPROP 0 LAST SIG_NAME FM_BATTERY_SENSE_EN_N
J 0
(-2300 -2240);
DISPLAY 0.680851 (-2300 -2240);
PAINT ORANGE (-2300 -2240);
WIRE 16 -1 (-2500 -2350)(-1300 -2350);
FORCEPROP 0 LAST SIG_NAME IRQ_PVDDQ_KLM_VRHOT_LVT3_N
J 0
(-2300 -2340);
DISPLAY 0.680851 (-2300 -2340);
PAINT ORANGE (-2300 -2340);
WIRE 3 682 (-1575 -3075)(-1425 -3075);
WIRE 3 682 (-1425 -3075)(-1425 -2825);
WIRE 3 682 (-1575 -2825)(-1575 -3075);
WIRE 3 682 (-1500 -2600)(-1450 -2600);
WIRE 3 682 (-1500 -2825)(-1575 -2825);
WIRE 3 682 (-1425 -2825)(-1500 -2825);
WIRE 3 682 (-1500 -2825)(-1500 -2600);
WIRE 2 -1 (-700 -2200)(-550 -2200);
WIRE 2 -1 (-550 -2150)(-550 -2200);
WIRE 2 -1 (-550 -2200)(-550 -2300);
WIRE 2 -1 (-550 -2300)(-700 -2300);
WIRE 16 -1 (-2500 -1350)(-1300 -1350);
FORCEPROP 0 LAST SIG_NAME SP2_BMC_CM_UART_TX
J 0
(-2300 -1340);
DISPLAY 0.680851 (-2300 -1340);
PAINT ORANGE (-2300 -1340);
WIRE 16 -1 (-2500 -1300)(-1300 -1300);
FORCEPROP 0 LAST SIG_NAME SP2_BMC_CM_UART_RX
J 0
(-2300 -1290);
DISPLAY 0.680851 (-2300 -1290);
PAINT ORANGE (-2300 -1290);
WIRE 16 -1 (-2500 -1450)(-1300 -1450);
FORCEPROP 0 LAST SIG_NAME FM_CPU0_THERMTRIP_LATCH_LVT3_N
J 0
(-2300 -1440);
DISPLAY 0.680851 (-2300 -1440);
PAINT ORANGE (-2300 -1440);
WIRE 16 -1 (-2500 -2650)(-850 -2650);
FORCEPROP 2 LAST SIG_NAME FM_CPU1_PROCHOT_LVT3_BMC_N
J 0
(-2300 -2640);
DISPLAY 0.680851 (-2300 -2640);
PAINT ORANGE (-2300 -2640);
WIRE 16 -1 (-2500 -2950)(-850 -2950);
FORCEPROP 0 LAST SIG_NAME RST_BMC_SYSRST_BTN_OUT_N
J 0
(-2300 -2940);
DISPLAY 0.680851 (-2300 -2940);
PAINT ORANGE (-2300 -2940);
WIRE 16 -1 (-2500 -2900)(-1600 -2900);
FORCEPROP 0 LAST SIG_NAME FM_PWR_BTN_R1_N
J 0
(-2300 -2890);
DISPLAY 0.680851 (-2300 -2890);
PAINT ORANGE (-2300 -2890);
FORCEPROP 2 LASTPROP $XRERR UNIQUE?
J 0
(-2540 -2890);
DISPLAY 0.638298 (-2540 -2890);
PAINT MONO (-2540 -2890);
DISPLAY INVISIBLE (-2540 -2890);
WIRE 16 -1 (-2500 -2700)(-850 -2700);
FORCEPROP 2 LAST SIG_NAME FM_CPU0_PROCHOT_LVT3_BMC_N
J 0
(-2300 -2690);
DISPLAY 0.680851 (-2300 -2690);
PAINT ORANGE (-2300 -2690);
WIRE 16 -1 (-6600 -3550)(-5450 -3550);
FORCEPROP 2 LAST SIG_NAME CLK_100M_BMC_PE_R_DP
J 0
(-6610 -3540);
DISPLAY 0.617021 (-6610 -3540);
PAINT ORANGE (-6610 -3540);
WIRE 16 -1 (-5450 -3550)(-5100 -3550);
WIRE 16 -1 (-5450 -4050)(-5450 -3550);
WIRE 16 -1 (-7050 -3975)(-7050 -4100);
WIRE 16 -1 (-7200 -3975)(-7050 -3975);
WIRE 16 -1 (-6600 -3975)(-7050 -3975);
FORCEPROP 2 LAST SIG_NAME FM_BMC_ONCTL_R_N
J 0
(-6985 -3965);
DISPLAY 0.617021 (-6985 -3965);
PAINT ORANGE (-6985 -3965);
WIRE 16 -1 (-6100 -2700)(-5100 -2700);
FORCEPROP 2 LAST SIG_NAME FM_BMC_ONCTL_R_N
J 0
(-6035 -2690);
DISPLAY 0.638298 (-6035 -2690);
PAINT ORANGE (-6035 -2690);
WIRE 16 -1 (-2500 -3200)(-1750 -3200);
FORCEPROP 0 LAST SIG_NAME PD_PEREXT
J 0
(-2300 -3190);
DISPLAY 0.680851 (-2300 -3190);
PAINT ORANGE (-2300 -3190);
FORCEPROP 2 LASTPROP $XRERR UNIQUE?
J 0
(-2540 -3190);
DISPLAY 0.638298 (-2540 -3190);
PAINT MONO (-2540 -3190);
DISPLAY INVISIBLE (-2540 -3190);
WIRE 16 -1 (-5050 -250)(-4550 -250);
FORCEPROP 2 LAST SIG_NAME CLK_25M_BMC
J 0
(-4985 -240);
DISPLAY 0.617021 (-4985 -240);
PAINT ORANGE (-4985 -240);
WIRE 16 -1 (-5350 -550)(-4550 -550);
FORCEPROP 2 LAST SIG_NAME CLK_24M_BMC_CLKIN_R
J 0
(-5260 -540);
DISPLAY 0.617021 (-5260 -540);
PAINT ORANGE (-5260 -540);
FORCEPROP 2 LASTPROP $XRERR UNIQUE?
J 0
(-5500 -540);
DISPLAY 0.638298 (-5500 -540);
PAINT MONO (-5500 -540);
DISPLAY INVISIBLE (-5500 -540);
WIRE 16 -1 (-7400 -3975)(-7950 -3975);
FORCEPROP 2 LAST SIG_NAME FM_BMC_ONCTL_N
J 0
(-7910 -3965);
DISPLAY 0.680851 (-7910 -3965);
PAINT ORANGE (-7910 -3965);
WIRE 16 -1 (-6550 -2350)(-7700 -2350);
FORCEPROP 2 LAST SIG_NAME SMB_DEBUG_STBY_LVC3_SCL
J 0
(-7635 -2340);
DISPLAY 0.638298 (-7635 -2340);
PAINT ORANGE (-7635 -2340);
WIRE 16 -1 (-6100 -1700)(-5100 -1700);
FORCEPROP 2 LAST SIG_NAME FM_BOARD_REV_ID0
J 0
(-6035 -1690);
DISPLAY 0.638298 (-6035 -1690);
PAINT ORANGE (-6035 -1690);
WIRE 16 -1 (-6100 -1300)(-5100 -1300);
FORCEPROP 2 LAST SIG_NAME FM_CPU_ERR1_LVT3_BMC_N
J 0
(-6035 -1290);
DISPLAY 0.638298 (-6035 -1290);
PAINT ORANGE (-6035 -1290);
WIRE 16 -1 (-6100 -1600)(-5100 -1600);
FORCEPROP 0 LAST CDS_PHYS_NET_NAME FM_SOL_UART_CH_SEL
J 0
(-5860 -1558);
PAINT MONO (-5860 -1558);
DISPLAY INVISIBLE (-5860 -1558);
FORCEPROP 2 LAST SIG_NAME FM_SOL_UART_CH_SEL
J 0
(-6035 -1590);
DISPLAY 0.638298 (-6035 -1590);
PAINT ORANGE (-6035 -1590);
WIRE 16 -1 (-6100 -1550)(-5100 -1550);
FORCEPROP 2 LAST SIG_NAME FM_BOARD_REV_ID1
J 0
(-6035 -1540);
DISPLAY 0.638298 (-6035 -1540);
PAINT ORANGE (-6035 -1540);
WIRE 16 -1 (-6100 -1500)(-5100 -1500);
FORCEPROP 0 LAST CDS_PHYS_NET_NAME IRQ_DIMM_SAVE_LVT3_N
J 0
(-6110 -1461);
PAINT MONO (-6110 -1461);
DISPLAY INVISIBLE (-6110 -1461);
FORCEPROP 0 LAST PHYS_NET_NAME IRQ_DIMM_SAVE_LVT3_N
J 0
(-6110 -1414);
PAINT MONO (-6110 -1414);
DISPLAY INVISIBLE (-6110 -1414);
FORCEPROP 2 LAST SIG_NAME IRQ_DIMM_SAVE_LVT3_N
J 0
(-6035 -1490);
DISPLAY 0.638298 (-6035 -1490);
PAINT ORANGE (-6035 -1490);
WIRE 16 -1 (-6100 -1450)(-5100 -1450);
FORCEPROP 2 LAST SIG_NAME FM_BOARD_REV_ID2
J 0
(-6035 -1440);
DISPLAY 0.638298 (-6035 -1440);
PAINT ORANGE (-6035 -1440);
WIRE 16 -1 (-6100 -2050)(-5100 -2050);
FORCEPROP 0 LAST SIG_NAME SMB_PEHPCPU1_STBY_LVC3_SCL
J 0
(-6035 -2040);
DISPLAY 0.617021 (-6035 -2040);
PAINT ORANGE (-6035 -2040);
WIRE 16 -1 (-4350 -250)(-4050 -250);
WIRE 16 -1 (-4050 -250)(-4050 -550);
WIRE 16 -1 (-4050 -550)(-3150 -550);
WIRE 16 -1 (-4350 -550)(-4050 -550);
FORCEPROP 2 LAST SIG_NAME CLK_24M_25M_BMC_CLKIN
J 0
(-3835 -540);
DISPLAY 0.617021 (-3835 -540);
PAINT ORANGE (-3835 -540);
WIRE 16 3135 (-2825 -325)(-2825 -100);
WIRE 16 3135 (-2825 -100)(-4650 -100);
WIRE 16 3135 (-3925 -325)(-2825 -325);
WIRE 16 3135 (-3925 -725)(-3925 -325);
WIRE 16 3135 (-4650 -100)(-4650 -725);
WIRE 16 3135 (-4650 -725)(-3925 -725);
WIRE 16 -1 (-7000 -650)(-6150 -650);
FORCEPROP 2 LAST SIG_NAME PU_24M_OSC_OE
J 0
(-6685 -640);
DISPLAY 0.617021 (-6685 -640);
PAINT ORANGE (-6685 -640);
FORCEPROP 2 LASTPROP $XRERR UNIQUE?
J 0
(-6925 -640);
DISPLAY 0.638298 (-6925 -640);
PAINT MONO (-6925 -640);
DISPLAY INVISIBLE (-6925 -640);
WIRE 16 -1 (-7000 -575)(-7000 -650);
WIRE 16 -1 (-7700 -1850)(-6550 -1850);
FORCEPROP 0 LAST SIG_NAME SMB_PEHPCPU0_STBY_LVC3_R_SDA
J 0
(-7635 -1840);
DISPLAY 0.617021 (-7635 -1840);
PAINT ORANGE (-7635 -1840);
WIRE 3 682 (-6750 -1450)(-6700 -1450);
WIRE 3 682 (-6750 -1750)(-6700 -1750);
WIRE 3 682 (-6750 -1500)(-6750 -1750);
WIRE 3 682 (-6750 -1450)(-6750 -1500);
WIRE 3 682 (-6850 -1500)(-6750 -1500);
WIRE 16 -1 (-5100 -1850)(-6350 -1850);
FORCEPROP 0 LAST SIG_NAME SMB_PEHPCPU0_STBY_LVC3_R2_SDA
J 0
(-6035 -1840);
DISPLAY 0.617021 (-6035 -1840);
PAINT ORANGE (-6035 -1840);
FORCEPROP 2 LASTPROP $XRERR UNIQUE?
J 0
(-6275 -1840);
DISPLAY 0.638298 (-6275 -1840);
PAINT MONO (-6275 -1840);
DISPLAY INVISIBLE (-6275 -1840);
WIRE 16 -1 (-5100 -1900)(-6350 -1900);
FORCEPROP 0 LAST SIG_NAME SMB_PEHPCPU0_STBY_LVC3_R2_SCL
J 0
(-6035 -1890);
DISPLAY 0.617021 (-6035 -1890);
PAINT ORANGE (-6035 -1890);
FORCEPROP 2 LASTPROP $XRERR UNIQUE?
J 0
(-6275 -1890);
DISPLAY 0.638298 (-6275 -1890);
PAINT MONO (-6275 -1890);
DISPLAY INVISIBLE (-6275 -1890);
WIRE 3 682 (-8100 -1950)(-8100 -1750);
WIRE 3 682 (-6825 -1950)(-8100 -1950);
WIRE 3 682 (-8100 -1750)(-6825 -1750);
WIRE 3 682 (-6825 -1750)(-6825 -1950);
WIRE 16 -1 (-6550 -1900)(-7700 -1900);
FORCEPROP 0 LAST SIG_NAME SMB_PEHPCPU0_STBY_LVC3_R_SCL
J 0
(-7635 -1890);
DISPLAY 0.617021 (-7635 -1890);
PAINT ORANGE (-7635 -1890);
WIRE 16 -1 (-6550 -2300)(-7700 -2300);
FORCEPROP 2 LAST SIG_NAME SMB_DEBUG_STBY_LVC3_SDA
J 0
(-7635 -2290);
DISPLAY 0.638298 (-7635 -2290);
PAINT ORANGE (-7635 -2290);
WIRE 16 -1 (-5100 -2150)(-7700 -2150);
FORCEPROP 0 LAST SIG_NAME SMB_PEHPCPU0_STBY_LVC3_SDA
J 0
(-7635 -2140);
DISPLAY 0.617021 (-7635 -2140);
PAINT ORANGE (-7635 -2140);
WIRE 16 -1 (-6600 -3450)(-6050 -3450);
FORCEPROP 2 LAST SIG_NAME RST_PLTRST_BUF_N
J 0
(-6610 -3440);
DISPLAY 0.617021 (-6610 -3440);
PAINT ORANGE (-6610 -3440);
WIRE 16 -1 (-7700 -3250)(-7650 -3250);
WIRE 16 -1 (-6550 -3250)(-7650 -3250);
FORCEPROP 2 LAST SIG_NAME PECI_BMC
J 0
(-7635 -3240);
DISPLAY 0.617021 (-7635 -3240);
PAINT ORANGE (-7635 -3240);
WIRE 16 -1 (-7650 -3325)(-7650 -3250);
WIRE 16 -1 (-6100 -2550)(-5100 -2550);
FORCEPROP 0 LAST CDS_PHYS_NET_NAME IRQ_OOB_MGMT_RISER_ALERT_N
J 0
(-5375 -2508);
PAINT MONO (-5375 -2508);
DISPLAY INVISIBLE (-5375 -2508);
FORCEPROP 2 LAST SIG_NAME IRQ_OOB_MGMT_RISER_ALERT_N
J 0
(-6035 -2540);
DISPLAY 0.638298 (-6035 -2540);
PAINT ORANGE (-6035 -2540);
WIRE 16 -1 (-6100 -2500)(-5100 -2500);
FORCEPROP 0 LAST CDS_PHYS_NET_NAME IRQ_MEZZ_LAN_ALERT_N
J 0
(-5100 -2461);
PAINT MONO (-5100 -2461);
DISPLAY INVISIBLE (-5100 -2461);
FORCEPROP 2 LAST SIG_NAME IRQ_MEZZ_LAN_ALERT_N
J 0
(-6035 -2490);
DISPLAY 0.638298 (-6035 -2490);
PAINT ORANGE (-6035 -2490);
FORCEPROP 0 LAST PHYS_NET_NAME IRQ_MEZZ_LAN_ALERT_N
J 0
(-5100 -2414);
PAINT MONO (-5100 -2414);
DISPLAY INVISIBLE (-5100 -2414);
WIRE 16 -1 (-6100 -2450)(-5100 -2450);
FORCEPROP 2 LAST SIG_NAME FM_BIOS_SMI_ACTIVE_N
J 0
(-6035 -2440);
DISPLAY 0.638298 (-6035 -2440);
PAINT ORANGE (-6035 -2440);
WIRE 16 -1 (-6350 -2350)(-5100 -2350);
FORCEPROP 2 LAST SIG_NAME SMB_DEBUG_STBY_LVC3_SCL_R
J 0
(-6035 -2340);
DISPLAY 0.638298 (-6035 -2340);
PAINT ORANGE (-6035 -2340);
FORCEPROP 2 LASTPROP $XRERR UNIQUE?
J 0
(-6275 -2340);
DISPLAY 0.638298 (-6275 -2340);
PAINT MONO (-6275 -2340);
DISPLAY INVISIBLE (-6275 -2340);
WIRE 16 -1 (-6350 -2300)(-5100 -2300);
FORCEPROP 2 LAST SIG_NAME SMB_DEBUG_STBY_LVC3_SDA_R
J 0
(-6035 -2290);
DISPLAY 0.638298 (-6035 -2290);
PAINT ORANGE (-6035 -2290);
FORCEPROP 2 LASTPROP $XRERR UNIQUE?
J 0
(-6275 -2290);
DISPLAY 0.638298 (-6275 -2290);
PAINT MONO (-6275 -2290);
DISPLAY INVISIBLE (-6275 -2290);
WIRE 16 -1 (-5100 -2200)(-7700 -2200);
FORCEPROP 0 LAST SIG_NAME SMB_PEHPCPU0_STBY_LVC3_SCL
J 0
(-7635 -2190);
DISPLAY 0.617021 (-7635 -2190);
PAINT ORANGE (-7635 -2190);
WIRE 16 -1 (-6100 -2600)(-5100 -2600);
FORCEPROP 2 LAST SIG_NAME IRQ_PCH_NIC_ALERT_N
J 0
(-6035 -2590);
DISPLAY 0.638298 (-6035 -2590);
PAINT ORANGE (-6035 -2590);
WIRE 16 -1 (-6100 -1350)(-5100 -1350);
FORCEPROP 2 LAST SIG_NAME FM_CPU_ERR0_LVT3_BMC_N
J 0
(-6035 -1340);
DISPLAY 0.638298 (-6035 -1340);
PAINT ORANGE (-6035 -1340);
WIRE 3 2175 (-1850 -4150)(-900 -4150);
WIRE 3 2175 (-900 -3150)(-900 -4150);
WIRE 3 2175 (-1850 -3150)(-1850 -4150);
WIRE 3 2175 (-1850 -3150)(-900 -3150);
WIRE 16 -1 (-1750 -3550)(-2350 -3550);
FORCEPROP 2 LAST SIG_NAME P2E_SSB_BMC_RX_DP
J 0
(-2310 -3540);
DISPLAY 0.680851 (-2310 -3540);
PAINT ORANGE (-2310 -3540);
FORCEPROP 2 LASTPROP $XRERR UNIQUE?
J 0
(-2550 -3540);
DISPLAY 0.638298 (-2550 -3540);
PAINT MONO (-2550 -3540);
DISPLAY INVISIBLE (-2550 -3540);
WIRE 16 -1 (-2350 -3300)(-2350 -3550);
WIRE 16 -1 (-2500 -3300)(-2350 -3300);
WIRE 16 -1 (-2500 -3000)(-1600 -3000);
FORCEPROP 0 LAST SIG_NAME RST_SYSTEM_BTN_R_N
J 0
(-2300 -2990);
DISPLAY 0.680851 (-2300 -2990);
PAINT ORANGE (-2300 -2990);
FORCEPROP 2 LASTPROP $XRERR UNIQUE?
J 0
(-2540 -2990);
DISPLAY 0.638298 (-2540 -2990);
PAINT MONO (-2540 -2990);
DISPLAY INVISIBLE (-2540 -2990);
WIRE 16 -1 (-2500 -2800)(-850 -2800);
FORCEPROP 0 LAST SIG_NAME FP_NMI_BTN_N
J 0
(-2300 -2790);
DISPLAY 0.680851 (-2300 -2790);
PAINT ORANGE (-2300 -2790);
WIRE 16 -1 (-2500 -2750)(-850 -2750);
FORCEPROP 0 LAST SIG_NAME IRQ_BMC_PCH_NMI_STBY_N
J 0
(-2300 -2740);
DISPLAY 0.680851 (-2300 -2740);
PAINT ORANGE (-2300 -2740);
WIRE 16 -1 (-2500 -2850)(-850 -2850);
FORCEPROP 0 LAST SIG_NAME FM_BMC_PWRBTN_OUT_N
J 0
(-2300 -2840);
DISPLAY 0.680851 (-2300 -2840);
PAINT ORANGE (-2300 -2840);
WIRE 16 -1 (-2500 -3100)(-850 -3100);
FORCEPROP 0 LAST SIG_NAME UART_BMC_TXD5
J 0
(-2300 -3090);
DISPLAY 0.680851 (-2300 -3090);
PAINT ORANGE (-2300 -3090);
WIRE 3 682 (-6250 -4450)(-4900 -4450);
WIRE 3 682 (-4900 -3900)(-4900 -4450);
WIRE 3 682 (-6250 -3900)(-6250 -4450);
WIRE 3 682 (-6250 -3900)(-4900 -3900);
WIRE 16 -1 (-2500 -2450)(-1300 -2450);
FORCEPROP 2 LAST SIG_NAME IRQ_PVCCIN_CPU0_VRHOT_LVC3_N
J 0
(-2300 -2440);
DISPLAY 0.680851 (-2300 -2440);
PAINT ORANGE (-2300 -2440);
WIRE 3 682 (-5400 -3175)(-5400 -3125);
WIRE 3 682 (-5350 -3175)(-5400 -3175);
WIRE 3 682 (-5400 -3125)(-5350 -3125);
WIRE 3 682 (-5350 -3125)(-5350 -3175);
WIRE 16 -1 (-6350 -2950)(-5100 -2950);
FORCEPROP 0 LAST CDS_PHYS_NET_NAME FM_BMC_SYS_THROTTLE_R_N
J 0
(-5960 -2908);
PAINT MONO (-5960 -2908);
DISPLAY INVISIBLE (-5960 -2908);
FORCEPROP 2 LAST SIG_NAME FM_BMC_SYS_THROTTLE_R_N
J 0
(-6035 -2940);
DISPLAY 0.638298 (-6035 -2940);
PAINT ORANGE (-6035 -2940);
FORCEPROP 2 LASTPROP $XRERR UNIQUE?
J 0
(-6275 -2940);
DISPLAY 0.638298 (-6275 -2940);
PAINT MONO (-6275 -2940);
DISPLAY INVISIBLE (-6275 -2940);
WIRE 3 682 (-5400 -2975)(-5400 -3025);
WIRE 3 682 (-5350 -2975)(-5400 -2975);
WIRE 3 682 (-5400 -3025)(-5350 -3025);
WIRE 3 682 (-5350 -3025)(-5350 -2975);
WIRE 16 -1 (-6100 -3100)(-5100 -3100);
FORCEPROP 0 LAST CDS_PHYS_NET_NAME FM_CPLD_BMC_PWRDN_N
J 0
(-6085 -3061);
PAINT MONO (-6085 -3061);
DISPLAY INVISIBLE (-6085 -3061);
FORCEPROP 2 LAST SIG_NAME FM_CPLD_BMC_PWRDN_N
J 0
(-6035 -3090);
DISPLAY 0.638298 (-6035 -3090);
PAINT ORANGE (-6035 -3090);
FORCEPROP 0 LAST PHYS_NET_NAME FM_CPLD_BMC_PWRDN_N
J 0
(-6085 -3014);
PAINT MONO (-6085 -3014);
DISPLAY INVISIBLE (-6085 -3014);
WIRE 16 -1 (-5100 -3150)(-6100 -3150);
FORCEPROP 2 LAST SIG_NAME JTAG_RISER_N
J 0
(-6035 -3140);
DISPLAY 0.638298 (-6035 -3140);
PAINT ORANGE (-6035 -3140);
WIRE 16 -1 (-6350 -3250)(-5100 -3250);
FORCEPROP 2 LAST SIG_NAME PECI_BMC_R
J 0
(-6035 -3240);
DISPLAY 0.617021 (-6035 -3240);
PAINT ORANGE (-6035 -3240);
FORCEPROP 2 LASTPROP $XRERR UNIQUE?
J 0
(-6275 -3240);
DISPLAY 0.638298 (-6275 -3240);
PAINT MONO (-6275 -3240);
DISPLAY INVISIBLE (-6275 -3240);
WIRE 3 682 (-6450 -3150)(-6850 -3150);
DOT 1 (-6750 -1500);
DOT 1 (-5200 -3450);
DOT 1 (-6200 -3750);
DOT 1 (-550 -2200);
DOT 1 (-5450 -3550);
DOT 1 (-5950 -3700);
DOT 1 (-7500 -300);
DOT 1 (-7000 -300);
DOT 1 (-4050 -550);
DOT 1 (-5700 -3600);
DOT 1 (-7050 -3975);
DOT 1 (-7650 -3250);
DOT 1 (-1500 -2825);
FORCENOTE
TP FAB1 REASSIGN GPIO PINS 0218
(-7825 -1500) 0;
DISPLAY LEFT (-7825 -1500);
DISPLAY 1.021277 (-7825 -1500);
PAINT RED (-7825 -1500);
FORCENOTE
TP FAB1 ADD TEST POINT 0314
(-6050 -3200) 0;
DISPLAY LEFT (-6050 -3200);
DISPLAY 0.638298 (-6050 -3200);
PAINT RED (-6050 -3200);
FORCENOTE
TP FAB1 ADD RES 0226
(-1425 -2625) 0;
DISPLAY LEFT (-1425 -2625);
DISPLAY 1.021277 (-1425 -2625);
PAINT RED (-1425 -2625);
FORCENOTE
TP FAB1 NOPOP WHEN AST2500 0106
(-6250 -4525) 0;
DISPLAY LEFT (-6250 -4525);
DISPLAY 1.021277 (-6250 -4525);
PAINT RED (-6250 -4525);
FORCENOTE
TP FAB1 POP WHEN AST2500 0106
(-6075 -3550) 0;
DISPLAY LEFT (-6075 -3550);
DISPLAY 0.638298 (-6075 -3550);
PAINT RED (-6075 -3550);
FORCENOTE
TP FAB1 CHANGE NET NAME 1218
(-1336 -2178) 0;
DISPLAY LEFT (-1336 -2178);
DISPLAY 1.021277 (-1336 -2178);
PAINT RED (-1336 -2178);
FORCENOTE
TP FAB1 CONNECT TO LEVEL SHIFT 0121
(-8275 -1700) 0;
DISPLAY LEFT (-8275 -1700);
DISPLAY 1.021277 (-8275 -1700);
PAINT RED (-8275 -1700);
FORCENOTE
ROOM=SM_CONTROLLER
(-7858 -4852) 0;
DISPLAY LEFT (-7858 -4852);
DISPLAY 0.617021 (-7858 -4852);
PAINT PURPLE (-7858 -4852);
FORCENOTE
ROOM=BMC
(-7875 -4675) 0;
DISPLAY LEFT (-7875 -4675);
DISPLAY 1.595745 (-7875 -4675);
PAINT PURPLE (-7875 -4675);
FORCENOTE
BOM_COST=SM_CONTROLLER
(-7875 -4775) 0;
DISPLAY LEFT (-7875 -4775);
DISPLAY 1.595745 (-7875 -4775);
PAINT PURPLE (-7875 -4775);
FORCENOTE
TP FAB1 CONNECT FROM DELAY IC 0229
(-8300 -2725) 0;
DISPLAY LEFT (-8300 -2725);
DISPLAY 1.021277 (-8300 -2725);
PAINT RED (-8300 -2725);
FORCENOTE
TP FAB1 POP WHEN AST2500 0106
(-1850 -4200) 0;
DISPLAY LEFT (-1850 -4200);
DISPLAY 0.638298 (-1850 -4200);
PAINT RED (-1850 -4200);
FORCENOTE
TP FAB1 ADD TEST POINT 0314
(-6050 -3050) 0;
DISPLAY LEFT (-6050 -3050);
DISPLAY 0.638298 (-6050 -3050);
PAINT RED (-6050 -3050);
FORCENOTE
TP FAB4 RECONNECT 20170111
(-7350 -3150) 0;
DISPLAY LEFT (-7350 -3150);
DISPLAY 0.510638 (-7350 -3150);
PAINT RED (-7350 -3150);
QUIT
